FILE_TYPE = MACRO_DRAWING;
SET COLOR_WIRE YELLOW;
SET COLOR_PROP ORANGE;
SET COLOR_DOT WHITE;
SET COLOR_ARC YELLOW;
SET COLOR_BODY GREEN;
SET COLOR_NOTE PURPLE;
SET PROP_DISPLAY VALUE;
SET PAGE_NUMBER P99;
FORCEADD OFFPAGE..5
(-8500 2000);
FORCEPROP 2 LAST $XR0 39 
J 0
(-8754 2000);
DISPLAY 0.638298 (-8754 2000);
PAINT MONO (-8754 2000);
FORCEPROP 2 LAST PATH I1
J 0
(-8750 2050);
DISPLAY 1.021277 (-8750 2050);
DISPLAY INVISIBLE (-8750 2050);
FORCEPROP 1 LAST COMMENT_BODY TRUE
J 0
(-8400 1925);
DISPLAY 0.872340 (-8400 1925);
PAINT GREEN (-8400 1925);
DISPLAY INVISIBLE (-8400 1925);
FORCEPROP 1 LAST OFFPAGE TRUE
J 0
(-8175 1875);
DISPLAY 0.872340 (-8175 1875);
PAINT GREEN (-8175 1875);
DISPLAY INVISIBLE (-8175 1875);
FORCEPROP 2 LAST CDS_LIB mstr_standard
J 0
(-8500 2000);
DISPLAY 0.808511 (-8500 2000);
DISPLAY INVISIBLE (-8500 2000);
FORCEADD OFFPAGE..6
(-8500 3600);
FORCEPROP 2 LAST $XR0 39 
J 0
(-8779 3600);
DISPLAY 0.638298 (-8779 3600);
PAINT MONO (-8779 3600);
FORCEPROP 2 LAST PATH I10
J 0
(-8775 3650);
DISPLAY 1.021277 (-8775 3650);
DISPLAY INVISIBLE (-8775 3650);
FORCEPROP 1 LAST COMMENT_BODY TRUE
J 0
(-8400 3525);
DISPLAY 0.872340 (-8400 3525);
PAINT GREEN (-8400 3525);
DISPLAY INVISIBLE (-8400 3525);
FORCEPROP 1 LAST OFFPAGE TRUE
J 0
(-8175 3475);
DISPLAY 0.872340 (-8175 3475);
PAINT GREEN (-8175 3475);
DISPLAY INVISIBLE (-8175 3475);
FORCEPROP 2 LAST CDS_LIB mstr_standard
J 0
(-8500 3600);
DISPLAY 0.723404 (-8500 3600);
PAINT MONO (-8500 3600);
DISPLAY INVISIBLE (-8500 3600);
FORCEADD TAP..1
(-6200 4000);
FORCEPROP 3 LASTPIN (-6250 4000) SIG_NAME M_C_CPU1_SA_DQ<3>
J 0
(-6240 4010);
DISPLAY 0.659574 (-6240 4010);
PAINT MONO (-6240 4010);
DISPLAY INVISIBLE (-6240 4010);
FORCEPROP 1 LASTPIN (-6250 4000) BN 3
J 0
(-6262 4008);
DISPLAY 0.489362 (-6262 4008);
PAINT GREEN (-6262 4008);
FORCEPROP 2 LAST CDS_LIB mstr_standard
J 0
(-6200 4000);
DISPLAY 0.723404 (-6200 4000);
PAINT MONO (-6200 4000);
DISPLAY INVISIBLE (-6200 4000);
FORCEPROP 1 LAST BODY_TYPE PLUMBING
J 0
(-6200 4050);
DISPLAY 0.872340 (-6200 4050);
PAINT GREEN (-6200 4050);
DISPLAY INVISIBLE (-6200 4050);
FORCEPROP 1 LAST HDL_TAP TRUE
J 0
(-5875 3875);
DISPLAY 0.872340 (-5875 3875);
DISPLAY INVISIBLE (-5875 3875);
FORCEPROP 1 LAST PATH I100
J 0
(-6202 4000);
DISPLAY 0.872340 (-6202 4000);
PAINT GREEN (-6202 4000);
DISPLAY INVISIBLE (-6202 4000);
FORCEADD TAP..1
(-6200 4050);
FORCEPROP 3 LASTPIN (-6250 4050) SIG_NAME M_C_CPU1_SA_DQ<4>
J 0
(-6240 4060);
DISPLAY 0.659574 (-6240 4060);
PAINT MONO (-6240 4060);
DISPLAY INVISIBLE (-6240 4060);
FORCEPROP 1 LASTPIN (-6250 4050) BN 4
J 0
(-6262 4058);
DISPLAY 0.489362 (-6262 4058);
PAINT GREEN (-6262 4058);
FORCEPROP 2 LAST CDS_LIB mstr_standard
J 0
(-6200 4050);
DISPLAY 0.723404 (-6200 4050);
PAINT MONO (-6200 4050);
DISPLAY INVISIBLE (-6200 4050);
FORCEPROP 1 LAST BODY_TYPE PLUMBING
J 0
(-6200 4100);
DISPLAY 0.872340 (-6200 4100);
PAINT GREEN (-6200 4100);
DISPLAY INVISIBLE (-6200 4100);
FORCEPROP 1 LAST HDL_TAP TRUE
J 0
(-5875 3925);
DISPLAY 0.872340 (-5875 3925);
DISPLAY INVISIBLE (-5875 3925);
FORCEPROP 1 LAST PATH I101
J 0
(-6202 4050);
DISPLAY 0.872340 (-6202 4050);
PAINT GREEN (-6202 4050);
DISPLAY INVISIBLE (-6202 4050);
FORCEADD TAP..1
(-6200 4100);
FORCEPROP 3 LASTPIN (-6250 4100) SIG_NAME M_C_CPU1_SA_DQ<5>
J 0
(-6240 4110);
DISPLAY 0.659574 (-6240 4110);
PAINT MONO (-6240 4110);
DISPLAY INVISIBLE (-6240 4110);
FORCEPROP 1 LASTPIN (-6250 4100) BN 5
J 0
(-6262 4108);
DISPLAY 0.489362 (-6262 4108);
PAINT GREEN (-6262 4108);
FORCEPROP 2 LAST CDS_LIB mstr_standard
J 0
(-6200 4100);
DISPLAY 0.723404 (-6200 4100);
PAINT MONO (-6200 4100);
DISPLAY INVISIBLE (-6200 4100);
FORCEPROP 1 LAST BODY_TYPE PLUMBING
J 0
(-6200 4150);
DISPLAY 0.872340 (-6200 4150);
PAINT GREEN (-6200 4150);
DISPLAY INVISIBLE (-6200 4150);
FORCEPROP 1 LAST HDL_TAP TRUE
J 0
(-5875 3975);
DISPLAY 0.872340 (-5875 3975);
DISPLAY INVISIBLE (-5875 3975);
FORCEPROP 1 LAST PATH I102
J 0
(-6202 4100);
DISPLAY 0.872340 (-6202 4100);
PAINT GREEN (-6202 4100);
DISPLAY INVISIBLE (-6202 4100);
FORCEADD TAP..1
(-6200 4150);
FORCEPROP 3 LASTPIN (-6250 4150) SIG_NAME M_C_CPU1_SA_DQ<6>
J 0
(-6240 4160);
DISPLAY 0.659574 (-6240 4160);
PAINT MONO (-6240 4160);
DISPLAY INVISIBLE (-6240 4160);
FORCEPROP 1 LASTPIN (-6250 4150) BN 6
J 0
(-6262 4158);
DISPLAY 0.489362 (-6262 4158);
PAINT GREEN (-6262 4158);
FORCEPROP 2 LAST CDS_LIB mstr_standard
J 0
(-6200 4150);
DISPLAY 0.723404 (-6200 4150);
PAINT MONO (-6200 4150);
DISPLAY INVISIBLE (-6200 4150);
FORCEPROP 1 LAST BODY_TYPE PLUMBING
J 0
(-6200 4200);
DISPLAY 0.872340 (-6200 4200);
PAINT GREEN (-6200 4200);
DISPLAY INVISIBLE (-6200 4200);
FORCEPROP 1 LAST HDL_TAP TRUE
J 0
(-5875 4025);
DISPLAY 0.872340 (-5875 4025);
DISPLAY INVISIBLE (-5875 4025);
FORCEPROP 1 LAST PATH I103
J 0
(-6202 4150);
DISPLAY 0.872340 (-6202 4150);
PAINT GREEN (-6202 4150);
DISPLAY INVISIBLE (-6202 4150);
FORCEADD TAP..1
(-6200 4200);
FORCEPROP 3 LASTPIN (-6250 4200) SIG_NAME M_C_CPU1_SA_DQ<7>
J 0
(-6240 4210);
DISPLAY 0.659574 (-6240 4210);
PAINT MONO (-6240 4210);
DISPLAY INVISIBLE (-6240 4210);
FORCEPROP 1 LASTPIN (-6250 4200) BN 7
J 0
(-6262 4208);
DISPLAY 0.489362 (-6262 4208);
PAINT GREEN (-6262 4208);
FORCEPROP 2 LAST CDS_LIB mstr_standard
J 0
(-6200 4200);
DISPLAY 0.723404 (-6200 4200);
PAINT MONO (-6200 4200);
DISPLAY INVISIBLE (-6200 4200);
FORCEPROP 1 LAST BODY_TYPE PLUMBING
J 0
(-6200 4250);
DISPLAY 0.872340 (-6200 4250);
PAINT GREEN (-6200 4250);
DISPLAY INVISIBLE (-6200 4250);
FORCEPROP 1 LAST HDL_TAP TRUE
J 0
(-5875 4075);
DISPLAY 0.872340 (-5875 4075);
DISPLAY INVISIBLE (-5875 4075);
FORCEPROP 1 LAST PATH I104
J 0
(-6202 4200);
DISPLAY 0.872340 (-6202 4200);
PAINT GREEN (-6202 4200);
DISPLAY INVISIBLE (-6202 4200);
FORCEADD TAP..1
(-6200 4300);
FORCEPROP 3 LASTPIN (-6250 4300) SIG_NAME M_C_CPU1_SA_DQ<9>
J 0
(-6240 4310);
DISPLAY 0.659574 (-6240 4310);
PAINT MONO (-6240 4310);
DISPLAY INVISIBLE (-6240 4310);
FORCEPROP 1 LASTPIN (-6250 4300) BN 9
J 0
(-6262 4308);
DISPLAY 0.489362 (-6262 4308);
PAINT GREEN (-6262 4308);
FORCEPROP 2 LAST CDS_LIB mstr_standard
J 0
(-6200 4300);
DISPLAY 0.723404 (-6200 4300);
PAINT MONO (-6200 4300);
DISPLAY INVISIBLE (-6200 4300);
FORCEPROP 1 LAST BODY_TYPE PLUMBING
J 0
(-6200 4350);
DISPLAY 0.872340 (-6200 4350);
PAINT GREEN (-6200 4350);
DISPLAY INVISIBLE (-6200 4350);
FORCEPROP 1 LAST HDL_TAP TRUE
J 0
(-5875 4175);
DISPLAY 0.872340 (-5875 4175);
DISPLAY INVISIBLE (-5875 4175);
FORCEPROP 1 LAST PATH I105
J 0
(-6202 4300);
DISPLAY 0.872340 (-6202 4300);
PAINT GREEN (-6202 4300);
DISPLAY INVISIBLE (-6202 4300);
FORCEADD TAP..1
(-6200 4350);
FORCEPROP 3 LASTPIN (-6250 4350) SIG_NAME M_C_CPU1_SA_DQ<10>
J 0
(-6240 4360);
DISPLAY 0.659574 (-6240 4360);
PAINT MONO (-6240 4360);
DISPLAY INVISIBLE (-6240 4360);
FORCEPROP 1 LASTPIN (-6250 4350) BN 10
J 0
(-6262 4358);
DISPLAY 0.489362 (-6262 4358);
PAINT GREEN (-6262 4358);
FORCEPROP 2 LAST CDS_LIB mstr_standard
J 0
(-6200 4350);
DISPLAY 0.723404 (-6200 4350);
PAINT MONO (-6200 4350);
DISPLAY INVISIBLE (-6200 4350);
FORCEPROP 1 LAST BODY_TYPE PLUMBING
J 0
(-6200 4400);
DISPLAY 0.872340 (-6200 4400);
PAINT GREEN (-6200 4400);
DISPLAY INVISIBLE (-6200 4400);
FORCEPROP 1 LAST HDL_TAP TRUE
J 0
(-5875 4225);
DISPLAY 0.872340 (-5875 4225);
DISPLAY INVISIBLE (-5875 4225);
FORCEPROP 1 LAST PATH I106
J 0
(-6202 4350);
DISPLAY 0.872340 (-6202 4350);
PAINT GREEN (-6202 4350);
DISPLAY INVISIBLE (-6202 4350);
FORCEADD TAP..1
(-6200 4250);
FORCEPROP 3 LASTPIN (-6250 4250) SIG_NAME M_C_CPU1_SA_DQ<8>
J 0
(-6240 4260);
DISPLAY 0.659574 (-6240 4260);
PAINT MONO (-6240 4260);
DISPLAY INVISIBLE (-6240 4260);
FORCEPROP 1 LASTPIN (-6250 4250) BN 8
J 0
(-6262 4258);
DISPLAY 0.489362 (-6262 4258);
PAINT GREEN (-6262 4258);
FORCEPROP 2 LAST CDS_LIB mstr_standard
J 0
(-6200 4250);
DISPLAY 0.723404 (-6200 4250);
PAINT MONO (-6200 4250);
DISPLAY INVISIBLE (-6200 4250);
FORCEPROP 1 LAST BODY_TYPE PLUMBING
J 0
(-6200 4300);
DISPLAY 0.872340 (-6200 4300);
PAINT GREEN (-6200 4300);
DISPLAY INVISIBLE (-6200 4300);
FORCEPROP 1 LAST HDL_TAP TRUE
J 0
(-5875 4125);
DISPLAY 0.872340 (-5875 4125);
DISPLAY INVISIBLE (-5875 4125);
FORCEPROP 1 LAST PATH I107
J 0
(-6202 4250);
DISPLAY 0.872340 (-6202 4250);
PAINT GREEN (-6202 4250);
DISPLAY INVISIBLE (-6202 4250);
FORCEADD TAP..1
(-6200 4400);
FORCEPROP 3 LASTPIN (-6250 4400) SIG_NAME M_C_CPU1_SA_DQ<11>
J 0
(-6240 4410);
DISPLAY 0.659574 (-6240 4410);
PAINT MONO (-6240 4410);
DISPLAY INVISIBLE (-6240 4410);
FORCEPROP 1 LASTPIN (-6250 4400) BN 11
J 0
(-6262 4408);
DISPLAY 0.489362 (-6262 4408);
PAINT GREEN (-6262 4408);
FORCEPROP 2 LAST CDS_LIB mstr_standard
J 0
(-6200 4400);
DISPLAY 0.723404 (-6200 4400);
PAINT MONO (-6200 4400);
DISPLAY INVISIBLE (-6200 4400);
FORCEPROP 1 LAST BODY_TYPE PLUMBING
J 0
(-6200 4450);
DISPLAY 0.872340 (-6200 4450);
PAINT GREEN (-6200 4450);
DISPLAY INVISIBLE (-6200 4450);
FORCEPROP 1 LAST HDL_TAP TRUE
J 0
(-5875 4275);
DISPLAY 0.872340 (-5875 4275);
DISPLAY INVISIBLE (-5875 4275);
FORCEPROP 1 LAST PATH I108
J 0
(-6202 4400);
DISPLAY 0.872340 (-6202 4400);
PAINT GREEN (-6202 4400);
DISPLAY INVISIBLE (-6202 4400);
FORCEADD TAP..1
(-6200 4450);
FORCEPROP 3 LASTPIN (-6250 4450) SIG_NAME M_C_CPU1_SA_DQ<12>
J 0
(-6240 4460);
DISPLAY 0.659574 (-6240 4460);
PAINT MONO (-6240 4460);
DISPLAY INVISIBLE (-6240 4460);
FORCEPROP 1 LASTPIN (-6250 4450) BN 12
J 0
(-6262 4458);
DISPLAY 0.489362 (-6262 4458);
PAINT GREEN (-6262 4458);
FORCEPROP 2 LAST CDS_LIB mstr_standard
J 0
(-6200 4450);
DISPLAY 0.723404 (-6200 4450);
PAINT MONO (-6200 4450);
DISPLAY INVISIBLE (-6200 4450);
FORCEPROP 1 LAST BODY_TYPE PLUMBING
J 0
(-6200 4500);
DISPLAY 0.872340 (-6200 4500);
PAINT GREEN (-6200 4500);
DISPLAY INVISIBLE (-6200 4500);
FORCEPROP 1 LAST HDL_TAP TRUE
J 0
(-5875 4325);
DISPLAY 0.872340 (-5875 4325);
DISPLAY INVISIBLE (-5875 4325);
FORCEPROP 1 LAST PATH I109
J 0
(-6202 4450);
DISPLAY 0.872340 (-6202 4450);
PAINT GREEN (-6202 4450);
DISPLAY INVISIBLE (-6202 4450);
FORCEADD OFFPAGE..6
(-8500 4050);
FORCEPROP 2 LAST $XR0 39 
J 0
(-8779 4050);
DISPLAY 0.638298 (-8779 4050);
PAINT MONO (-8779 4050);
FORCEPROP 2 LAST PATH I11
J 0
(-8775 4100);
DISPLAY 1.021277 (-8775 4100);
DISPLAY INVISIBLE (-8775 4100);
FORCEPROP 1 LAST COMMENT_BODY TRUE
J 0
(-8400 3975);
DISPLAY 0.872340 (-8400 3975);
PAINT GREEN (-8400 3975);
DISPLAY INVISIBLE (-8400 3975);
FORCEPROP 1 LAST OFFPAGE TRUE
J 0
(-8175 3925);
DISPLAY 0.872340 (-8175 3925);
PAINT GREEN (-8175 3925);
DISPLAY INVISIBLE (-8175 3925);
FORCEPROP 2 LAST CDS_LIB mstr_standard
J 0
(-8500 4050);
DISPLAY 0.723404 (-8500 4050);
PAINT MONO (-8500 4050);
DISPLAY INVISIBLE (-8500 4050);
FORCEADD TAP..1
(-6200 4550);
FORCEPROP 3 LASTPIN (-6250 4550) SIG_NAME M_C_CPU1_SA_DQ<14>
J 0
(-6240 4560);
DISPLAY 0.659574 (-6240 4560);
PAINT MONO (-6240 4560);
DISPLAY INVISIBLE (-6240 4560);
FORCEPROP 1 LASTPIN (-6250 4550) BN 14
J 0
(-6262 4558);
DISPLAY 0.489362 (-6262 4558);
PAINT GREEN (-6262 4558);
FORCEPROP 2 LAST CDS_LIB mstr_standard
J 0
(-6200 4550);
DISPLAY 0.723404 (-6200 4550);
PAINT MONO (-6200 4550);
DISPLAY INVISIBLE (-6200 4550);
FORCEPROP 1 LAST BODY_TYPE PLUMBING
J 0
(-6200 4600);
DISPLAY 0.872340 (-6200 4600);
PAINT GREEN (-6200 4600);
DISPLAY INVISIBLE (-6200 4600);
FORCEPROP 1 LAST HDL_TAP TRUE
J 0
(-5875 4425);
DISPLAY 0.872340 (-5875 4425);
DISPLAY INVISIBLE (-5875 4425);
FORCEPROP 1 LAST PATH I110
J 0
(-6202 4550);
DISPLAY 0.872340 (-6202 4550);
PAINT GREEN (-6202 4550);
DISPLAY INVISIBLE (-6202 4550);
FORCEADD TAP..1
(-6200 4600);
FORCEPROP 3 LASTPIN (-6250 4600) SIG_NAME M_C_CPU1_SA_DQ<15>
J 0
(-6240 4610);
DISPLAY 0.659574 (-6240 4610);
PAINT MONO (-6240 4610);
DISPLAY INVISIBLE (-6240 4610);
FORCEPROP 1 LASTPIN (-6250 4600) BN 15
J 0
(-6262 4608);
DISPLAY 0.489362 (-6262 4608);
PAINT GREEN (-6262 4608);
FORCEPROP 2 LAST CDS_LIB mstr_standard
J 0
(-6200 4600);
DISPLAY 0.723404 (-6200 4600);
PAINT MONO (-6200 4600);
DISPLAY INVISIBLE (-6200 4600);
FORCEPROP 1 LAST BODY_TYPE PLUMBING
J 0
(-6200 4650);
DISPLAY 0.872340 (-6200 4650);
PAINT GREEN (-6200 4650);
DISPLAY INVISIBLE (-6200 4650);
FORCEPROP 1 LAST HDL_TAP TRUE
J 0
(-5875 4475);
DISPLAY 0.872340 (-5875 4475);
DISPLAY INVISIBLE (-5875 4475);
FORCEPROP 1 LAST PATH I111
J 0
(-6202 4600);
DISPLAY 0.872340 (-6202 4600);
PAINT GREEN (-6202 4600);
DISPLAY INVISIBLE (-6202 4600);
FORCEADD TAP..1
(-6200 4500);
FORCEPROP 3 LASTPIN (-6250 4500) SIG_NAME M_C_CPU1_SA_DQ<13>
J 0
(-6240 4510);
DISPLAY 0.659574 (-6240 4510);
PAINT MONO (-6240 4510);
DISPLAY INVISIBLE (-6240 4510);
FORCEPROP 1 LASTPIN (-6250 4500) BN 13
J 0
(-6262 4508);
DISPLAY 0.489362 (-6262 4508);
PAINT GREEN (-6262 4508);
FORCEPROP 2 LAST CDS_LIB mstr_standard
J 0
(-6200 4500);
DISPLAY 0.723404 (-6200 4500);
PAINT MONO (-6200 4500);
DISPLAY INVISIBLE (-6200 4500);
FORCEPROP 1 LAST BODY_TYPE PLUMBING
J 0
(-6200 4550);
DISPLAY 0.872340 (-6200 4550);
PAINT GREEN (-6200 4550);
DISPLAY INVISIBLE (-6200 4550);
FORCEPROP 1 LAST HDL_TAP TRUE
J 0
(-5875 4375);
DISPLAY 0.872340 (-5875 4375);
DISPLAY INVISIBLE (-5875 4375);
FORCEPROP 1 LAST PATH I112
J 0
(-6202 4500);
DISPLAY 0.872340 (-6202 4500);
PAINT GREEN (-6202 4500);
DISPLAY INVISIBLE (-6202 4500);
FORCEADD TAP..1
(-6200 4650);
FORCEPROP 3 LASTPIN (-6250 4650) SIG_NAME M_C_CPU1_SA_DQ<16>
J 0
(-6240 4660);
DISPLAY 0.659574 (-6240 4660);
PAINT MONO (-6240 4660);
DISPLAY INVISIBLE (-6240 4660);
FORCEPROP 1 LASTPIN (-6250 4650) BN 16
J 0
(-6262 4658);
DISPLAY 0.489362 (-6262 4658);
PAINT GREEN (-6262 4658);
FORCEPROP 2 LAST CDS_LIB mstr_standard
J 0
(-6200 4650);
DISPLAY 0.723404 (-6200 4650);
PAINT MONO (-6200 4650);
DISPLAY INVISIBLE (-6200 4650);
FORCEPROP 1 LAST BODY_TYPE PLUMBING
J 0
(-6200 4700);
DISPLAY 0.872340 (-6200 4700);
PAINT GREEN (-6200 4700);
DISPLAY INVISIBLE (-6200 4700);
FORCEPROP 1 LAST HDL_TAP TRUE
J 0
(-5875 4525);
DISPLAY 0.872340 (-5875 4525);
DISPLAY INVISIBLE (-5875 4525);
FORCEPROP 1 LAST PATH I113
J 0
(-6202 4650);
DISPLAY 0.872340 (-6202 4650);
PAINT GREEN (-6202 4650);
DISPLAY INVISIBLE (-6202 4650);
FORCEADD TAP..1
(-6200 4700);
FORCEPROP 3 LASTPIN (-6250 4700) SIG_NAME M_C_CPU1_SA_DQ<17>
J 0
(-6240 4710);
DISPLAY 0.659574 (-6240 4710);
PAINT MONO (-6240 4710);
DISPLAY INVISIBLE (-6240 4710);
FORCEPROP 1 LASTPIN (-6250 4700) BN 17
J 0
(-6262 4708);
DISPLAY 0.489362 (-6262 4708);
PAINT GREEN (-6262 4708);
FORCEPROP 2 LAST CDS_LIB mstr_standard
J 0
(-6200 4700);
DISPLAY 0.723404 (-6200 4700);
PAINT MONO (-6200 4700);
DISPLAY INVISIBLE (-6200 4700);
FORCEPROP 1 LAST BODY_TYPE PLUMBING
J 0
(-6200 4750);
DISPLAY 0.872340 (-6200 4750);
PAINT GREEN (-6200 4750);
DISPLAY INVISIBLE (-6200 4750);
FORCEPROP 1 LAST HDL_TAP TRUE
J 0
(-5875 4575);
DISPLAY 0.872340 (-5875 4575);
DISPLAY INVISIBLE (-5875 4575);
FORCEPROP 1 LAST PATH I114
J 0
(-6202 4700);
DISPLAY 0.872340 (-6202 4700);
PAINT GREEN (-6202 4700);
DISPLAY INVISIBLE (-6202 4700);
FORCEADD TAP..1
(-6200 4850);
FORCEPROP 3 LASTPIN (-6250 4850) SIG_NAME M_C_CPU1_SA_DQ<20>
J 0
(-6240 4860);
DISPLAY 0.659574 (-6240 4860);
PAINT MONO (-6240 4860);
DISPLAY INVISIBLE (-6240 4860);
FORCEPROP 1 LASTPIN (-6250 4850) BN 20
J 0
(-6262 4858);
DISPLAY 0.489362 (-6262 4858);
PAINT GREEN (-6262 4858);
FORCEPROP 2 LAST CDS_LIB mstr_standard
J 0
(-6200 4850);
DISPLAY 0.723404 (-6200 4850);
PAINT MONO (-6200 4850);
DISPLAY INVISIBLE (-6200 4850);
FORCEPROP 1 LAST BODY_TYPE PLUMBING
J 0
(-6200 4900);
DISPLAY 0.872340 (-6200 4900);
PAINT GREEN (-6200 4900);
DISPLAY INVISIBLE (-6200 4900);
FORCEPROP 1 LAST HDL_TAP TRUE
J 0
(-5875 4725);
DISPLAY 0.872340 (-5875 4725);
DISPLAY INVISIBLE (-5875 4725);
FORCEPROP 1 LAST PATH I115
J 0
(-6202 4850);
DISPLAY 0.872340 (-6202 4850);
PAINT GREEN (-6202 4850);
DISPLAY INVISIBLE (-6202 4850);
FORCEADD TAP..1
(-6200 4800);
FORCEPROP 3 LASTPIN (-6250 4800) SIG_NAME M_C_CPU1_SA_DQ<19>
J 0
(-6240 4810);
DISPLAY 0.659574 (-6240 4810);
PAINT MONO (-6240 4810);
DISPLAY INVISIBLE (-6240 4810);
FORCEPROP 1 LASTPIN (-6250 4800) BN 19
J 0
(-6262 4808);
DISPLAY 0.489362 (-6262 4808);
PAINT GREEN (-6262 4808);
FORCEPROP 2 LAST CDS_LIB mstr_standard
J 0
(-6200 4800);
DISPLAY 0.723404 (-6200 4800);
PAINT MONO (-6200 4800);
DISPLAY INVISIBLE (-6200 4800);
FORCEPROP 1 LAST BODY_TYPE PLUMBING
J 0
(-6200 4850);
DISPLAY 0.872340 (-6200 4850);
PAINT GREEN (-6200 4850);
DISPLAY INVISIBLE (-6200 4850);
FORCEPROP 1 LAST HDL_TAP TRUE
J 0
(-5875 4675);
DISPLAY 0.872340 (-5875 4675);
DISPLAY INVISIBLE (-5875 4675);
FORCEPROP 1 LAST PATH I116
J 0
(-6202 4800);
DISPLAY 0.872340 (-6202 4800);
PAINT GREEN (-6202 4800);
DISPLAY INVISIBLE (-6202 4800);
FORCEADD TAP..1
(-6200 4750);
FORCEPROP 3 LASTPIN (-6250 4750) SIG_NAME M_C_CPU1_SA_DQ<18>
J 0
(-6240 4760);
DISPLAY 0.659574 (-6240 4760);
PAINT MONO (-6240 4760);
DISPLAY INVISIBLE (-6240 4760);
FORCEPROP 1 LASTPIN (-6250 4750) BN 18
J 0
(-6262 4758);
DISPLAY 0.489362 (-6262 4758);
PAINT GREEN (-6262 4758);
FORCEPROP 2 LAST CDS_LIB mstr_standard
J 0
(-6200 4750);
DISPLAY 0.723404 (-6200 4750);
PAINT MONO (-6200 4750);
DISPLAY INVISIBLE (-6200 4750);
FORCEPROP 1 LAST BODY_TYPE PLUMBING
J 0
(-6200 4800);
DISPLAY 0.872340 (-6200 4800);
PAINT GREEN (-6200 4800);
DISPLAY INVISIBLE (-6200 4800);
FORCEPROP 1 LAST HDL_TAP TRUE
J 0
(-5875 4625);
DISPLAY 0.872340 (-5875 4625);
DISPLAY INVISIBLE (-5875 4625);
FORCEPROP 1 LAST PATH I117
J 0
(-6202 4750);
DISPLAY 0.872340 (-6202 4750);
PAINT GREEN (-6202 4750);
DISPLAY INVISIBLE (-6202 4750);
FORCEADD TAP..1
(-6200 4900);
FORCEPROP 3 LASTPIN (-6250 4900) SIG_NAME M_C_CPU1_SA_DQ<21>
J 0
(-6240 4910);
DISPLAY 0.659574 (-6240 4910);
PAINT MONO (-6240 4910);
DISPLAY INVISIBLE (-6240 4910);
FORCEPROP 1 LASTPIN (-6250 4900) BN 21
J 0
(-6262 4908);
DISPLAY 0.489362 (-6262 4908);
PAINT GREEN (-6262 4908);
FORCEPROP 2 LAST CDS_LIB mstr_standard
J 0
(-6200 4900);
DISPLAY 0.723404 (-6200 4900);
PAINT MONO (-6200 4900);
DISPLAY INVISIBLE (-6200 4900);
FORCEPROP 1 LAST BODY_TYPE PLUMBING
J 0
(-6200 4950);
DISPLAY 0.872340 (-6200 4950);
PAINT GREEN (-6200 4950);
DISPLAY INVISIBLE (-6200 4950);
FORCEPROP 1 LAST HDL_TAP TRUE
J 0
(-5875 4775);
DISPLAY 0.872340 (-5875 4775);
DISPLAY INVISIBLE (-5875 4775);
FORCEPROP 1 LAST PATH I118
J 0
(-6202 4900);
DISPLAY 0.872340 (-6202 4900);
PAINT GREEN (-6202 4900);
DISPLAY INVISIBLE (-6202 4900);
FORCEADD TAP..1
(-6200 4950);
FORCEPROP 3 LASTPIN (-6250 4950) SIG_NAME M_C_CPU1_SA_DQ<22>
J 0
(-6240 4960);
DISPLAY 0.659574 (-6240 4960);
PAINT MONO (-6240 4960);
DISPLAY INVISIBLE (-6240 4960);
FORCEPROP 1 LASTPIN (-6250 4950) BN 22
J 0
(-6262 4958);
DISPLAY 0.489362 (-6262 4958);
PAINT GREEN (-6262 4958);
FORCEPROP 2 LAST CDS_LIB mstr_standard
J 0
(-6200 4950);
DISPLAY 0.723404 (-6200 4950);
PAINT MONO (-6200 4950);
DISPLAY INVISIBLE (-6200 4950);
FORCEPROP 1 LAST BODY_TYPE PLUMBING
J 0
(-6200 5000);
DISPLAY 0.872340 (-6200 5000);
PAINT GREEN (-6200 5000);
DISPLAY INVISIBLE (-6200 5000);
FORCEPROP 1 LAST HDL_TAP TRUE
J 0
(-5875 4825);
DISPLAY 0.872340 (-5875 4825);
DISPLAY INVISIBLE (-5875 4825);
FORCEPROP 1 LAST PATH I119
J 0
(-6202 4950);
DISPLAY 0.872340 (-6202 4950);
PAINT GREEN (-6202 4950);
DISPLAY INVISIBLE (-6202 4950);
FORCEADD OFFPAGE..1
(-8500 4100);
FORCEPROP 2 LAST $XR0 39 
J 0
(-8721 4100);
DISPLAY 0.638298 (-8721 4100);
PAINT MONO (-8721 4100);
FORCEPROP 2 LAST PATH I12
J 0
(-8700 4150);
DISPLAY 1.021277 (-8700 4150);
DISPLAY INVISIBLE (-8700 4150);
FORCEPROP 1 LAST COMMENT_BODY TRUE
J 0
(-8375 4000);
DISPLAY 0.872340 (-8375 4000);
PAINT GREEN (-8375 4000);
DISPLAY INVISIBLE (-8375 4000);
FORCEPROP 1 LAST OFFPAGE TRUE
J 0
(-8175 3975);
DISPLAY 0.872340 (-8175 3975);
PAINT GREEN (-8175 3975);
DISPLAY INVISIBLE (-8175 3975);
FORCEPROP 2 LAST CDS_LIB mstr_standard
J 0
(-8500 4100);
DISPLAY 0.808511 (-8500 4100);
DISPLAY INVISIBLE (-8500 4100);
FORCEADD TAP..1
(-6200 5000);
FORCEPROP 3 LASTPIN (-6250 5000) SIG_NAME M_C_CPU1_SA_DQ<23>
J 0
(-6240 5010);
DISPLAY 0.659574 (-6240 5010);
PAINT MONO (-6240 5010);
DISPLAY INVISIBLE (-6240 5010);
FORCEPROP 1 LASTPIN (-6250 5000) BN 23
J 0
(-6262 5008);
DISPLAY 0.489362 (-6262 5008);
PAINT GREEN (-6262 5008);
FORCEPROP 2 LAST CDS_LIB mstr_standard
J 0
(-6200 5000);
DISPLAY 0.723404 (-6200 5000);
PAINT MONO (-6200 5000);
DISPLAY INVISIBLE (-6200 5000);
FORCEPROP 1 LAST BODY_TYPE PLUMBING
J 0
(-6200 5050);
DISPLAY 0.872340 (-6200 5050);
PAINT GREEN (-6200 5050);
DISPLAY INVISIBLE (-6200 5050);
FORCEPROP 1 LAST HDL_TAP TRUE
J 0
(-5875 4875);
DISPLAY 0.872340 (-5875 4875);
DISPLAY INVISIBLE (-5875 4875);
FORCEPROP 1 LAST PATH I120
J 0
(-6202 5000);
DISPLAY 0.872340 (-6202 5000);
PAINT GREEN (-6202 5000);
DISPLAY INVISIBLE (-6202 5000);
FORCEADD TAP..1
(-6200 5050);
FORCEPROP 3 LASTPIN (-6250 5050) SIG_NAME M_C_CPU1_SA_DQ<24>
J 0
(-6240 5060);
DISPLAY 0.659574 (-6240 5060);
PAINT MONO (-6240 5060);
DISPLAY INVISIBLE (-6240 5060);
FORCEPROP 1 LASTPIN (-6250 5050) BN 24
J 0
(-6262 5058);
DISPLAY 0.489362 (-6262 5058);
PAINT GREEN (-6262 5058);
FORCEPROP 2 LAST CDS_LIB mstr_standard
J 0
(-6200 5050);
DISPLAY 0.723404 (-6200 5050);
PAINT MONO (-6200 5050);
DISPLAY INVISIBLE (-6200 5050);
FORCEPROP 1 LAST BODY_TYPE PLUMBING
J 0
(-6200 5100);
DISPLAY 0.872340 (-6200 5100);
PAINT GREEN (-6200 5100);
DISPLAY INVISIBLE (-6200 5100);
FORCEPROP 1 LAST HDL_TAP TRUE
J 0
(-5875 4925);
DISPLAY 0.872340 (-5875 4925);
DISPLAY INVISIBLE (-5875 4925);
FORCEPROP 1 LAST PATH I121
J 0
(-6202 5050);
DISPLAY 0.872340 (-6202 5050);
PAINT GREEN (-6202 5050);
DISPLAY INVISIBLE (-6202 5050);
FORCEADD TAP..1
(-6200 5100);
FORCEPROP 3 LASTPIN (-6250 5100) SIG_NAME M_C_CPU1_SA_DQ<25>
J 0
(-6240 5110);
DISPLAY 0.659574 (-6240 5110);
PAINT MONO (-6240 5110);
DISPLAY INVISIBLE (-6240 5110);
FORCEPROP 1 LASTPIN (-6250 5100) BN 25
J 0
(-6262 5108);
DISPLAY 0.489362 (-6262 5108);
PAINT GREEN (-6262 5108);
FORCEPROP 2 LAST CDS_LIB mstr_standard
J 0
(-6200 5100);
DISPLAY 0.723404 (-6200 5100);
PAINT MONO (-6200 5100);
DISPLAY INVISIBLE (-6200 5100);
FORCEPROP 1 LAST BODY_TYPE PLUMBING
J 0
(-6200 5150);
DISPLAY 0.872340 (-6200 5150);
PAINT GREEN (-6200 5150);
DISPLAY INVISIBLE (-6200 5150);
FORCEPROP 1 LAST HDL_TAP TRUE
J 0
(-5875 4975);
DISPLAY 0.872340 (-5875 4975);
DISPLAY INVISIBLE (-5875 4975);
FORCEPROP 1 LAST PATH I122
J 0
(-6202 5100);
DISPLAY 0.872340 (-6202 5100);
PAINT GREEN (-6202 5100);
DISPLAY INVISIBLE (-6202 5100);
FORCEADD TAP..1
(-6200 5250);
FORCEPROP 3 LASTPIN (-6250 5250) SIG_NAME M_C_CPU1_SA_DQ<28>
J 0
(-6240 5260);
DISPLAY 0.659574 (-6240 5260);
PAINT MONO (-6240 5260);
DISPLAY INVISIBLE (-6240 5260);
FORCEPROP 1 LASTPIN (-6250 5250) BN 28
J 0
(-6262 5258);
DISPLAY 0.489362 (-6262 5258);
PAINT GREEN (-6262 5258);
FORCEPROP 2 LAST CDS_LIB mstr_standard
J 0
(-6200 5250);
DISPLAY 0.723404 (-6200 5250);
PAINT MONO (-6200 5250);
DISPLAY INVISIBLE (-6200 5250);
FORCEPROP 1 LAST BODY_TYPE PLUMBING
J 0
(-6200 5300);
DISPLAY 0.872340 (-6200 5300);
PAINT GREEN (-6200 5300);
DISPLAY INVISIBLE (-6200 5300);
FORCEPROP 1 LAST HDL_TAP TRUE
J 0
(-5875 5125);
DISPLAY 0.872340 (-5875 5125);
DISPLAY INVISIBLE (-5875 5125);
FORCEPROP 1 LAST PATH I123
J 0
(-6202 5250);
DISPLAY 0.872340 (-6202 5250);
PAINT GREEN (-6202 5250);
DISPLAY INVISIBLE (-6202 5250);
FORCEADD TAP..1
(-6200 5200);
FORCEPROP 3 LASTPIN (-6250 5200) SIG_NAME M_C_CPU1_SA_DQ<27>
J 0
(-6240 5210);
DISPLAY 0.659574 (-6240 5210);
PAINT MONO (-6240 5210);
DISPLAY INVISIBLE (-6240 5210);
FORCEPROP 1 LASTPIN (-6250 5200) BN 27
J 0
(-6262 5208);
DISPLAY 0.489362 (-6262 5208);
PAINT GREEN (-6262 5208);
FORCEPROP 2 LAST CDS_LIB mstr_standard
J 0
(-6200 5200);
DISPLAY 0.723404 (-6200 5200);
PAINT MONO (-6200 5200);
DISPLAY INVISIBLE (-6200 5200);
FORCEPROP 1 LAST BODY_TYPE PLUMBING
J 0
(-6200 5250);
DISPLAY 0.872340 (-6200 5250);
PAINT GREEN (-6200 5250);
DISPLAY INVISIBLE (-6200 5250);
FORCEPROP 1 LAST HDL_TAP TRUE
J 0
(-5875 5075);
DISPLAY 0.872340 (-5875 5075);
DISPLAY INVISIBLE (-5875 5075);
FORCEPROP 1 LAST PATH I124
J 0
(-6202 5200);
DISPLAY 0.872340 (-6202 5200);
PAINT GREEN (-6202 5200);
DISPLAY INVISIBLE (-6202 5200);
FORCEADD TAP..1
(-6200 5150);
FORCEPROP 3 LASTPIN (-6250 5150) SIG_NAME M_C_CPU1_SA_DQ<26>
J 0
(-6240 5160);
DISPLAY 0.659574 (-6240 5160);
PAINT MONO (-6240 5160);
DISPLAY INVISIBLE (-6240 5160);
FORCEPROP 1 LASTPIN (-6250 5150) BN 26
J 0
(-6262 5158);
DISPLAY 0.489362 (-6262 5158);
PAINT GREEN (-6262 5158);
FORCEPROP 2 LAST CDS_LIB mstr_standard
J 0
(-6200 5150);
DISPLAY 0.723404 (-6200 5150);
PAINT MONO (-6200 5150);
DISPLAY INVISIBLE (-6200 5150);
FORCEPROP 1 LAST BODY_TYPE PLUMBING
J 0
(-6200 5200);
DISPLAY 0.872340 (-6200 5200);
PAINT GREEN (-6200 5200);
DISPLAY INVISIBLE (-6200 5200);
FORCEPROP 1 LAST HDL_TAP TRUE
J 0
(-5875 5025);
DISPLAY 0.872340 (-5875 5025);
DISPLAY INVISIBLE (-5875 5025);
FORCEPROP 1 LAST PATH I125
J 0
(-6202 5150);
DISPLAY 0.872340 (-6202 5150);
PAINT GREEN (-6202 5150);
DISPLAY INVISIBLE (-6202 5150);
FORCEADD TAP..1
(-6200 5300);
FORCEPROP 3 LASTPIN (-6250 5300) SIG_NAME M_C_CPU1_SA_DQ<29>
J 0
(-6240 5310);
DISPLAY 0.659574 (-6240 5310);
PAINT MONO (-6240 5310);
DISPLAY INVISIBLE (-6240 5310);
FORCEPROP 1 LASTPIN (-6250 5300) BN 29
J 0
(-6262 5308);
DISPLAY 0.489362 (-6262 5308);
PAINT GREEN (-6262 5308);
FORCEPROP 2 LAST CDS_LIB mstr_standard
J 0
(-6200 5300);
DISPLAY 0.723404 (-6200 5300);
PAINT MONO (-6200 5300);
DISPLAY INVISIBLE (-6200 5300);
FORCEPROP 1 LAST BODY_TYPE PLUMBING
J 0
(-6200 5350);
DISPLAY 0.872340 (-6200 5350);
PAINT GREEN (-6200 5350);
DISPLAY INVISIBLE (-6200 5350);
FORCEPROP 1 LAST HDL_TAP TRUE
J 0
(-5875 5175);
DISPLAY 0.872340 (-5875 5175);
DISPLAY INVISIBLE (-5875 5175);
FORCEPROP 1 LAST PATH I126
J 0
(-6202 5300);
DISPLAY 0.872340 (-6202 5300);
PAINT GREEN (-6202 5300);
DISPLAY INVISIBLE (-6202 5300);
FORCEADD TAP..1
(-6200 5350);
FORCEPROP 3 LASTPIN (-6250 5350) SIG_NAME M_C_CPU1_SA_DQ<30>
J 0
(-6240 5360);
DISPLAY 0.659574 (-6240 5360);
PAINT MONO (-6240 5360);
DISPLAY INVISIBLE (-6240 5360);
FORCEPROP 1 LASTPIN (-6250 5350) BN 30
J 0
(-6262 5358);
DISPLAY 0.489362 (-6262 5358);
PAINT GREEN (-6262 5358);
FORCEPROP 2 LAST CDS_LIB mstr_standard
J 0
(-6200 5350);
DISPLAY 0.723404 (-6200 5350);
PAINT MONO (-6200 5350);
DISPLAY INVISIBLE (-6200 5350);
FORCEPROP 1 LAST BODY_TYPE PLUMBING
J 0
(-6200 5400);
DISPLAY 0.872340 (-6200 5400);
PAINT GREEN (-6200 5400);
DISPLAY INVISIBLE (-6200 5400);
FORCEPROP 1 LAST HDL_TAP TRUE
J 0
(-5875 5225);
DISPLAY 0.872340 (-5875 5225);
DISPLAY INVISIBLE (-5875 5225);
FORCEPROP 1 LAST PATH I127
J 0
(-6202 5350);
DISPLAY 0.872340 (-6202 5350);
PAINT GREEN (-6202 5350);
DISPLAY INVISIBLE (-6202 5350);
FORCEADD TAP..1
(-6200 5400);
FORCEPROP 3 LASTPIN (-6250 5400) SIG_NAME M_C_CPU1_SA_DQ<31>
J 0
(-6240 5410);
DISPLAY 0.659574 (-6240 5410);
PAINT MONO (-6240 5410);
DISPLAY INVISIBLE (-6240 5410);
FORCEPROP 1 LASTPIN (-6250 5400) BN 31
J 0
(-6262 5408);
DISPLAY 0.489362 (-6262 5408);
PAINT GREEN (-6262 5408);
FORCEPROP 2 LAST CDS_LIB mstr_standard
J 0
(-6200 5400);
DISPLAY 0.723404 (-6200 5400);
PAINT MONO (-6200 5400);
DISPLAY INVISIBLE (-6200 5400);
FORCEPROP 1 LAST BODY_TYPE PLUMBING
J 0
(-6200 5450);
DISPLAY 0.872340 (-6200 5450);
PAINT GREEN (-6200 5450);
DISPLAY INVISIBLE (-6200 5450);
FORCEPROP 1 LAST HDL_TAP TRUE
J 0
(-5875 5275);
DISPLAY 0.872340 (-5875 5275);
DISPLAY INVISIBLE (-5875 5275);
FORCEPROP 1 LAST PATH I128
J 0
(-6202 5400);
DISPLAY 0.872340 (-6202 5400);
PAINT GREEN (-6202 5400);
DISPLAY INVISIBLE (-6202 5400);
FORCEADD OFFPAGE..3
(-5600 5450);
FORCEPROP 2 LAST $XR0 39 
J 0
(-5386 5450);
DISPLAY 0.638298 (-5386 5450);
PAINT MONO (-5386 5450);
FORCEPROP 2 LAST PATH I129
J 0
(-5375 5500);
DISPLAY 1.021277 (-5375 5500);
DISPLAY INVISIBLE (-5375 5500);
FORCEPROP 1 LAST COMMENT_BODY TRUE
J 0
(-5650 5350);
DISPLAY 0.872340 (-5650 5350);
PAINT GREEN (-5650 5350);
DISPLAY INVISIBLE (-5650 5350);
FORCEPROP 1 LAST OFFPAGE TRUE
J 0
(-5275 5325);
DISPLAY 0.872340 (-5275 5325);
PAINT GREEN (-5275 5325);
DISPLAY INVISIBLE (-5275 5325);
FORCEPROP 2 LAST CDS_LIB mstr_standard
J 0
(-5600 5450);
DISPLAY 0.723404 (-5600 5450);
PAINT MONO (-5600 5450);
DISPLAY INVISIBLE (-5600 5450);
FORCEADD OFFPAGE..1
(-8500 4300);
FORCEPROP 2 LAST $XR0 39 
J 0
(-8721 4300);
DISPLAY 0.638298 (-8721 4300);
PAINT MONO (-8721 4300);
FORCEPROP 2 LAST PATH I13
J 0
(-8700 4350);
DISPLAY 1.021277 (-8700 4350);
DISPLAY INVISIBLE (-8700 4350);
FORCEPROP 1 LAST COMMENT_BODY TRUE
J 0
(-8375 4200);
DISPLAY 0.872340 (-8375 4200);
PAINT GREEN (-8375 4200);
DISPLAY INVISIBLE (-8375 4200);
FORCEPROP 1 LAST OFFPAGE TRUE
J 0
(-8175 4175);
DISPLAY 0.872340 (-8175 4175);
PAINT GREEN (-8175 4175);
DISPLAY INVISIBLE (-8175 4175);
FORCEPROP 2 LAST CDS_LIB mstr_standard
J 0
(-8500 4300);
DISPLAY 0.723404 (-8500 4300);
PAINT MONO (-8500 4300);
DISPLAY INVISIBLE (-8500 4300);
FORCEADD OFFPAGE..1
(-8500 4250);
FORCEPROP 2 LAST $XR0 39 
J 0
(-8721 4250);
DISPLAY 0.638298 (-8721 4250);
PAINT MONO (-8721 4250);
FORCEPROP 2 LAST PATH I14
J 0
(-8700 4300);
DISPLAY 1.021277 (-8700 4300);
DISPLAY INVISIBLE (-8700 4300);
FORCEPROP 1 LAST COMMENT_BODY TRUE
J 0
(-8375 4150);
DISPLAY 0.872340 (-8375 4150);
PAINT GREEN (-8375 4150);
DISPLAY INVISIBLE (-8375 4150);
FORCEPROP 1 LAST OFFPAGE TRUE
J 0
(-8175 4125);
DISPLAY 0.872340 (-8175 4125);
PAINT GREEN (-8175 4125);
DISPLAY INVISIBLE (-8175 4125);
FORCEPROP 2 LAST CDS_LIB mstr_standard
J 0
(-8500 4250);
DISPLAY 0.808511 (-8500 4250);
DISPLAY INVISIBLE (-8500 4250);
FORCEADD OFFPAGE..5
(-7375 1425);
FORCEPROP 2 LAST $XR0 99 
J 0
(-7629 1425);
DISPLAY 0.638298 (-7629 1425);
PAINT MONO (-7629 1425);
FORCEPROP 2 LAST PATH I146
J 0
(-7625 1475);
DISPLAY 1.021277 (-7625 1475);
DISPLAY INVISIBLE (-7625 1475);
FORCEPROP 1 LAST COMMENT_BODY TRUE
J 0
(-7275 1350);
DISPLAY 0.872340 (-7275 1350);
PAINT GREEN (-7275 1350);
DISPLAY INVISIBLE (-7275 1350);
FORCEPROP 1 LAST OFFPAGE TRUE
J 0
(-7050 1300);
DISPLAY 0.872340 (-7050 1300);
PAINT GREEN (-7050 1300);
DISPLAY INVISIBLE (-7050 1300);
FORCEPROP 2 LAST BOM_COST MEM
J 0
(-7450 1500);
DISPLAY 0.808511 (-7450 1500);
DISPLAY INVISIBLE (-7450 1500);
FORCEPROP 2 LAST CDS_LIB mstr_standard
J 0
(-7375 1425);
DISPLAY 0.808511 (-7375 1425);
DISPLAY INVISIBLE (-7375 1425);
FORCEADD GND..1
(-6600 1025);
FORCEPROP 3 LASTPIN (-6600 1075) SIG_NAME GND\g
J 0
(-6590 1085);
DISPLAY 0.659574 (-6590 1085);
PAINT MONO (-6590 1085);
DISPLAY INVISIBLE (-6590 1085);
FORCEPROP 1 LAST SIZE 1B
J 0
(-6525 975);
DISPLAY 0.851064 (-6525 975);
PAINT GREEN (-6525 975);
DISPLAY INVISIBLE (-6525 975);
FORCEPROP 2 LAST BOM_COST MEM
J 0
(-6700 1100);
DISPLAY 0.808511 (-6700 1100);
DISPLAY INVISIBLE (-6700 1100);
FORCEPROP 2 LAST CDS_LIB mstr_symbols
J 0
(-6600 1025);
DISPLAY 0.808511 (-6600 1025);
DISPLAY INVISIBLE (-6600 1025);
FORCEPROP 1 LAST BODY_TYPE PLUMBING
J 0
(-6645 982);
DISPLAY 0.340426 (-6645 982);
PAINT GREEN (-6645 982);
DISPLAY INVISIBLE (-6645 982);
FORCEPROP 1 LAST PATH I147
J 0
(-6525 1025);
DISPLAY 0.872340 (-6525 1025);
PAINT AQUA (-6525 1025);
DISPLAY INVISIBLE (-6525 1025);
FORCEPROP 1 LAST VOLTAGE 0.0
J 0
(-6645 982);
DISPLAY 0.723404 (-6645 982);
PAINT SKYBLUE (-6645 982);
DISPLAY INVISIBLE (-6645 982);
FORCEPROP 1 LAST HDL_POWER GND
J 0
(-6600 1175);
DISPLAY 0.851064 (-6600 1175);
PAINT GREEN (-6600 1175);
DISPLAY INVISIBLE (-6600 1175);
FORCEADD Q_RES..2
(-6600 1250);
FORCEPROP 1 LAST LOCATION R771
J 0
(-6555 1375);
DISPLAY 0.489362 (-6555 1375);
PAINT SKYBLUE (-6555 1375);
FORCEPROP 0 LAST $SEC 1
J 0
(-6550 1425);
DISPLAY 0.680851 (-6550 1425);
PAINT MONO (-6550 1425);
DISPLAY INVISIBLE (-6550 1425);
FORCEPROP 0 LAST CDS_SEC 1
J 0
(-6550 1425);
DISPLAY 1.021277 (-6550 1425);
DISPLAY INVISIBLE (-6550 1425);
FORCEPROP 1 LASTPIN (-6600 1350) $PN 1
J 0
(-6595 1312);
DISPLAY 0.489362 (-6595 1312);
PAINT MONO (-6595 1312);
FORCEPROP 1 LASTPIN (-6600 1150) $PN 2
J 0
(-6595 1160);
DISPLAY 0.489362 (-6595 1160);
PAINT MONO (-6595 1160);
FORCEPROP 1 LAST WATTAGE 1/16W
J 0
(-6560 1225);
DISPLAY 0.489362 (-6560 1225);
PAINT SKYBLUE (-6560 1225);
FORCEPROP 1 LAST MATERIAL CHIP
J 0
(-6560 1175);
DISPLAY 0.489362 (-6560 1175);
PAINT SKYBLUE (-6560 1175);
FORCEPROP 1 LAST TOLERANCE 1%
J 0
(-6555 1275);
DISPLAY 0.489362 (-6555 1275);
PAINT SKYBLUE (-6555 1275);
FORCEPROP 1 LAST VALUE 23.2K
J 0
(-6555 1325);
DISPLAY 0.489362 (-6555 1325);
PAINT SKYBLUE (-6555 1325);
FORCEPROP 1 LAST PART_NUMBER TMP_QCS32322FB11
J 0
(-6560 1125);
DISPLAY 0.489362 (-6560 1125);
PAINT SKYBLUE (-6560 1125);
FORCEPROP 1 LAST PACK_TYPE 0402LF
J 0
(-6560 1075);
DISPLAY 0.489362 (-6560 1075);
PAINT SKYBLUE (-6560 1075);
FORCEPROP 2 LAST CDS_LIB pure_quanta
J 0
(-6600 1250);
DISPLAY INVISIBLE (-6600 1250);
FORCEPROP 1 LAST PATH I148
J 0
(-6550 1425);
DISPLAY 0.978723 (-6550 1425);
PAINT WHITE (-6550 1425);
DISPLAY INVISIBLE (-6550 1425);
FORCEADD OFFPAGE..1
(-8500 4150);
FORCEPROP 2 LAST $XR0 39 
J 0
(-8721 4150);
DISPLAY 0.638298 (-8721 4150);
PAINT MONO (-8721 4150);
FORCEPROP 2 LAST PATH I15
J 0
(-8700 4200);
DISPLAY 1.021277 (-8700 4200);
DISPLAY INVISIBLE (-8700 4200);
FORCEPROP 1 LAST COMMENT_BODY TRUE
J 0
(-8375 4050);
DISPLAY 0.872340 (-8375 4050);
PAINT GREEN (-8375 4050);
DISPLAY INVISIBLE (-8375 4050);
FORCEPROP 1 LAST OFFPAGE TRUE
J 0
(-8175 4025);
DISPLAY 0.872340 (-8175 4025);
PAINT GREEN (-8175 4025);
DISPLAY INVISIBLE (-8175 4025);
FORCEPROP 2 LAST CDS_LIB mstr_standard
J 0
(-8500 4150);
DISPLAY 0.723404 (-8500 4150);
PAINT MONO (-8500 4150);
DISPLAY INVISIBLE (-8500 4150);
FORCEADD GND..1
(-2225 2000);
FORCEPROP 3 LASTPIN (-2225 2050) SIG_NAME GND\g
J 0
(-2215 2060);
DISPLAY 0.659574 (-2215 2060);
PAINT MONO (-2215 2060);
DISPLAY INVISIBLE (-2215 2060);
FORCEPROP 1 LAST SIZE 1B
J 0
(-2150 1950);
DISPLAY 0.851064 (-2150 1950);
PAINT GREEN (-2150 1950);
DISPLAY INVISIBLE (-2150 1950);
FORCEPROP 2 LAST CDS_LIB mstr_symbols
J 0
(-2225 2000);
DISPLAY 0.723404 (-2225 2000);
DISPLAY INVISIBLE (-2225 2000);
FORCEPROP 1 LAST BODY_TYPE PLUMBING
J 0
(-2270 1957);
DISPLAY 0.340426 (-2270 1957);
PAINT GREEN (-2270 1957);
DISPLAY INVISIBLE (-2270 1957);
FORCEPROP 1 LAST PATH I154
J 0
(-2150 2000);
DISPLAY 0.872340 (-2150 2000);
PAINT AQUA (-2150 2000);
DISPLAY INVISIBLE (-2150 2000);
FORCEPROP 1 LAST VOLTAGE 0.0
J 0
(-2270 1957);
DISPLAY 0.723404 (-2270 1957);
PAINT SKYBLUE (-2270 1957);
DISPLAY INVISIBLE (-2270 1957);
FORCEPROP 1 LAST HDL_POWER GND
J 0
(-2225 2150);
DISPLAY 0.851064 (-2225 2150);
PAINT GREEN (-2225 2150);
DISPLAY INVISIBLE (-2225 2150);
FORCEADD SCONN288_DDR506112002KQ..3
(-1325 3750);
FORCEPROP 1 LAST LOCATION J28
J 0
(-1775 5725);
DISPLAY 0.468085 (-1775 5725);
PAINT SKYBLUE (-1775 5725);
FORCEPROP 0 LAST $SEC 3
J 0
(-1775 5875);
DISPLAY 0.680851 (-1775 5875);
PAINT MONO (-1775 5875);
DISPLAY INVISIBLE (-1775 5875);
FORCEPROP 2 LAST CDS_SEC 3
J 0
(-1775 5875);
DISPLAY 1.021277 (-1775 5875);
DISPLAY INVISIBLE (-1775 5875);
FORCEPROP 0 LASTPIN (-725 2150) $PN G1
J 0
(-715 2160);
DISPLAY 0.680851 (-715 2160);
PAINT MONO (-715 2160);
FORCEPROP 0 LASTPIN (-725 2100) $PN G2
J 0
(-715 2110);
DISPLAY 0.680851 (-715 2110);
PAINT MONO (-715 2110);
FORCEPROP 0 LASTPIN (-725 2050) $PN G3
J 0
(-715 2060);
DISPLAY 0.680851 (-715 2060);
PAINT MONO (-715 2060);
FORCEPROP 0 LASTPIN (-1925 5300) $PN 1
J 2
(-1935 5310);
DISPLAY 0.680851 (-1935 5310);
PAINT MONO (-1935 5310);
FORCEPROP 0 LASTPIN (-1925 5350) $PN 145
J 2
(-1935 5360);
DISPLAY 0.680851 (-1935 5360);
PAINT MONO (-1935 5360);
FORCEPROP 0 LASTPIN (-1925 5400) $PN 146
J 2
(-1935 5410);
DISPLAY 0.680851 (-1935 5410);
PAINT MONO (-1935 5410);
FORCEPROP 0 LASTPIN (-725 2250) $PN 6
J 0
(-715 2260);
DISPLAY 0.680851 (-715 2260);
PAINT MONO (-715 2260);
FORCEPROP 0 LASTPIN (-725 2300) $PN 8
J 0
(-715 2310);
DISPLAY 0.680851 (-715 2310);
PAINT MONO (-715 2310);
FORCEPROP 0 LASTPIN (-725 2350) $PN 10
J 0
(-715 2360);
DISPLAY 0.680851 (-715 2360);
PAINT MONO (-715 2360);
FORCEPROP 0 LASTPIN (-725 2400) $PN 13
J 0
(-715 2410);
DISPLAY 0.680851 (-715 2410);
PAINT MONO (-715 2410);
FORCEPROP 0 LASTPIN (-725 2450) $PN 15
J 0
(-715 2460);
DISPLAY 0.680851 (-715 2460);
PAINT MONO (-715 2460);
FORCEPROP 0 LASTPIN (-725 2500) $PN 17
J 0
(-715 2510);
DISPLAY 0.680851 (-715 2510);
PAINT MONO (-715 2510);
FORCEPROP 0 LASTPIN (-725 2550) $PN 19
J 0
(-715 2560);
DISPLAY 0.680851 (-715 2560);
PAINT MONO (-715 2560);
FORCEPROP 0 LASTPIN (-725 2600) $PN 21
J 0
(-715 2610);
DISPLAY 0.680851 (-715 2610);
PAINT MONO (-715 2610);
FORCEPROP 0 LASTPIN (-725 2650) $PN 24
J 0
(-715 2660);
DISPLAY 0.680851 (-715 2660);
PAINT MONO (-715 2660);
FORCEPROP 0 LASTPIN (-725 2700) $PN 26
J 0
(-715 2710);
DISPLAY 0.680851 (-715 2710);
PAINT MONO (-715 2710);
FORCEPROP 0 LASTPIN (-725 2750) $PN 28
J 0
(-715 2760);
DISPLAY 0.680851 (-715 2760);
PAINT MONO (-715 2760);
FORCEPROP 0 LASTPIN (-725 2800) $PN 30
J 0
(-715 2810);
DISPLAY 0.680851 (-715 2810);
PAINT MONO (-715 2810);
FORCEPROP 0 LASTPIN (-725 2850) $PN 32
J 0
(-715 2860);
DISPLAY 0.680851 (-715 2860);
PAINT MONO (-715 2860);
FORCEPROP 0 LASTPIN (-725 2900) $PN 35
J 0
(-715 2910);
DISPLAY 0.680851 (-715 2910);
PAINT MONO (-715 2910);
FORCEPROP 0 LASTPIN (-725 2950) $PN 37
J 0
(-715 2960);
DISPLAY 0.680851 (-715 2960);
PAINT MONO (-715 2960);
FORCEPROP 0 LASTPIN (-725 3000) $PN 39
J 0
(-715 3010);
DISPLAY 0.680851 (-715 3010);
PAINT MONO (-715 3010);
FORCEPROP 0 LASTPIN (-725 3050) $PN 41
J 0
(-715 3060);
DISPLAY 0.680851 (-715 3060);
PAINT MONO (-715 3060);
FORCEPROP 0 LASTPIN (-725 3100) $PN 43
J 0
(-715 3110);
DISPLAY 0.680851 (-715 3110);
PAINT MONO (-715 3110);
FORCEPROP 0 LASTPIN (-725 3150) $PN 46
J 0
(-715 3160);
DISPLAY 0.680851 (-715 3160);
PAINT MONO (-715 3160);
FORCEPROP 0 LASTPIN (-725 3200) $PN 48
J 0
(-715 3210);
DISPLAY 0.680851 (-715 3210);
PAINT MONO (-715 3210);
FORCEPROP 0 LASTPIN (-725 3250) $PN 50
J 0
(-715 3260);
DISPLAY 0.680851 (-715 3260);
PAINT MONO (-715 3260);
FORCEPROP 0 LASTPIN (-725 3300) $PN 52
J 0
(-715 3310);
DISPLAY 0.680851 (-715 3310);
PAINT MONO (-715 3310);
FORCEPROP 0 LASTPIN (-725 3350) $PN 54
J 0
(-715 3360);
DISPLAY 0.680851 (-715 3360);
PAINT MONO (-715 3360);
FORCEPROP 0 LASTPIN (-725 3400) $PN 57
J 0
(-715 3410);
DISPLAY 0.680851 (-715 3410);
PAINT MONO (-715 3410);
FORCEPROP 0 LASTPIN (-725 3450) $PN 59
J 0
(-715 3460);
DISPLAY 0.680851 (-715 3460);
PAINT MONO (-715 3460);
FORCEPROP 0 LASTPIN (-725 3500) $PN 61
J 0
(-715 3510);
DISPLAY 0.680851 (-715 3510);
PAINT MONO (-715 3510);
FORCEPROP 0 LASTPIN (-725 3550) $PN 63
J 0
(-715 3560);
DISPLAY 0.680851 (-715 3560);
PAINT MONO (-715 3560);
FORCEPROP 0 LASTPIN (-725 3600) $PN 65
J 0
(-715 3610);
DISPLAY 0.680851 (-715 3610);
PAINT MONO (-715 3610);
FORCEPROP 0 LASTPIN (-725 3650) $PN 67
J 0
(-715 3660);
DISPLAY 0.680851 (-715 3660);
PAINT MONO (-715 3660);
FORCEPROP 0 LASTPIN (-725 3700) $PN 69
J 0
(-715 3710);
DISPLAY 0.680851 (-715 3710);
PAINT MONO (-715 3710);
FORCEPROP 0 LASTPIN (-725 3750) $PN 71
J 0
(-715 3760);
DISPLAY 0.680851 (-715 3760);
PAINT MONO (-715 3760);
FORCEPROP 0 LASTPIN (-725 3800) $PN 73
J 0
(-715 3810);
DISPLAY 0.680851 (-715 3810);
PAINT MONO (-715 3810);
FORCEPROP 0 LASTPIN (-725 3850) $PN 75
J 0
(-715 3860);
DISPLAY 0.680851 (-715 3860);
PAINT MONO (-715 3860);
FORCEPROP 0 LASTPIN (-725 3900) $PN 77
J 0
(-715 3910);
DISPLAY 0.680851 (-715 3910);
PAINT MONO (-715 3910);
FORCEPROP 0 LASTPIN (-725 3950) $PN 79
J 0
(-715 3960);
DISPLAY 0.680851 (-715 3960);
PAINT MONO (-715 3960);
FORCEPROP 0 LASTPIN (-725 4000) $PN 81
J 0
(-715 4010);
DISPLAY 0.680851 (-715 4010);
PAINT MONO (-715 4010);
FORCEPROP 0 LASTPIN (-725 4050) $PN 83
J 0
(-715 4060);
DISPLAY 0.680851 (-715 4060);
PAINT MONO (-715 4060);
FORCEPROP 0 LASTPIN (-725 4100) $PN 85
J 0
(-715 4110);
DISPLAY 0.680851 (-715 4110);
PAINT MONO (-715 4110);
FORCEPROP 0 LASTPIN (-725 4150) $PN 88
J 0
(-715 4160);
DISPLAY 0.680851 (-715 4160);
PAINT MONO (-715 4160);
FORCEPROP 0 LASTPIN (-725 4200) $PN 90
J 0
(-715 4210);
DISPLAY 0.680851 (-715 4210);
PAINT MONO (-715 4210);
FORCEPROP 0 LASTPIN (-725 4250) $PN 92
J 0
(-715 4260);
DISPLAY 0.680851 (-715 4260);
PAINT MONO (-715 4260);
FORCEPROP 0 LASTPIN (-725 4300) $PN 95
J 0
(-715 4310);
DISPLAY 0.680851 (-715 4310);
PAINT MONO (-715 4310);
FORCEPROP 0 LASTPIN (-725 4350) $PN 97
J 0
(-715 4360);
DISPLAY 0.680851 (-715 4360);
PAINT MONO (-715 4360);
FORCEPROP 0 LASTPIN (-725 4400) $PN 99
J 0
(-715 4410);
DISPLAY 0.680851 (-715 4410);
PAINT MONO (-715 4410);
FORCEPROP 0 LASTPIN (-725 4450) $PN 101
J 0
(-715 4460);
DISPLAY 0.680851 (-715 4460);
PAINT MONO (-715 4460);
FORCEPROP 0 LASTPIN (-725 4500) $PN 103
J 0
(-715 4510);
DISPLAY 0.680851 (-715 4510);
PAINT MONO (-715 4510);
FORCEPROP 0 LASTPIN (-725 4550) $PN 106
J 0
(-715 4560);
DISPLAY 0.680851 (-715 4560);
PAINT MONO (-715 4560);
FORCEPROP 0 LASTPIN (-725 4600) $PN 108
J 0
(-715 4610);
DISPLAY 0.680851 (-715 4610);
PAINT MONO (-715 4610);
FORCEPROP 0 LASTPIN (-725 4650) $PN 110
J 0
(-715 4660);
DISPLAY 0.680851 (-715 4660);
PAINT MONO (-715 4660);
FORCEPROP 0 LASTPIN (-725 4700) $PN 112
J 0
(-715 4710);
DISPLAY 0.680851 (-715 4710);
PAINT MONO (-715 4710);
FORCEPROP 0 LASTPIN (-725 4750) $PN 114
J 0
(-715 4760);
DISPLAY 0.680851 (-715 4760);
PAINT MONO (-715 4760);
FORCEPROP 0 LASTPIN (-725 4800) $PN 117
J 0
(-715 4810);
DISPLAY 0.680851 (-715 4810);
PAINT MONO (-715 4810);
FORCEPROP 0 LASTPIN (-725 4850) $PN 119
J 0
(-715 4860);
DISPLAY 0.680851 (-715 4860);
PAINT MONO (-715 4860);
FORCEPROP 0 LASTPIN (-725 4900) $PN 121
J 0
(-715 4910);
DISPLAY 0.680851 (-715 4910);
PAINT MONO (-715 4910);
FORCEPROP 0 LASTPIN (-725 4950) $PN 123
J 0
(-715 4960);
DISPLAY 0.680851 (-715 4960);
PAINT MONO (-715 4960);
FORCEPROP 0 LASTPIN (-725 5000) $PN 125
J 0
(-715 5010);
DISPLAY 0.680851 (-715 5010);
PAINT MONO (-715 5010);
FORCEPROP 0 LASTPIN (-725 5050) $PN 128
J 0
(-715 5060);
DISPLAY 0.680851 (-715 5060);
PAINT MONO (-715 5060);
FORCEPROP 0 LASTPIN (-725 5100) $PN 130
J 0
(-715 5110);
DISPLAY 0.680851 (-715 5110);
PAINT MONO (-715 5110);
FORCEPROP 0 LASTPIN (-725 5150) $PN 132
J 0
(-715 5160);
DISPLAY 0.680851 (-715 5160);
PAINT MONO (-715 5160);
FORCEPROP 0 LASTPIN (-725 5200) $PN 134
J 0
(-715 5210);
DISPLAY 0.680851 (-715 5210);
PAINT MONO (-715 5210);
FORCEPROP 0 LASTPIN (-725 5250) $PN 136
J 0
(-715 5260);
DISPLAY 0.680851 (-715 5260);
PAINT MONO (-715 5260);
FORCEPROP 0 LASTPIN (-725 5300) $PN 139
J 0
(-715 5310);
DISPLAY 0.680851 (-715 5310);
PAINT MONO (-715 5310);
FORCEPROP 0 LASTPIN (-725 5350) $PN 141
J 0
(-715 5360);
DISPLAY 0.680851 (-715 5360);
PAINT MONO (-715 5360);
FORCEPROP 0 LASTPIN (-725 5400) $PN 143
J 0
(-715 5410);
DISPLAY 0.680851 (-715 5410);
PAINT MONO (-715 5410);
FORCEPROP 0 LASTPIN (-1925 2150) $PN 151
J 2
(-1935 2160);
DISPLAY 0.680851 (-1935 2160);
PAINT MONO (-1935 2160);
FORCEPROP 0 LASTPIN (-1925 2200) $PN 153
J 2
(-1935 2210);
DISPLAY 0.680851 (-1935 2210);
PAINT MONO (-1935 2210);
FORCEPROP 0 LASTPIN (-1925 2250) $PN 155
J 2
(-1935 2260);
DISPLAY 0.680851 (-1935 2260);
PAINT MONO (-1935 2260);
FORCEPROP 0 LASTPIN (-1925 2300) $PN 158
J 2
(-1935 2310);
DISPLAY 0.680851 (-1935 2310);
PAINT MONO (-1935 2310);
FORCEPROP 0 LASTPIN (-1925 2350) $PN 160
J 2
(-1935 2360);
DISPLAY 0.680851 (-1935 2360);
PAINT MONO (-1935 2360);
FORCEPROP 0 LASTPIN (-1925 2400) $PN 162
J 2
(-1935 2410);
DISPLAY 0.680851 (-1935 2410);
PAINT MONO (-1935 2410);
FORCEPROP 0 LASTPIN (-1925 2450) $PN 164
J 2
(-1935 2460);
DISPLAY 0.680851 (-1935 2460);
PAINT MONO (-1935 2460);
FORCEPROP 0 LASTPIN (-1925 2500) $PN 166
J 2
(-1935 2510);
DISPLAY 0.680851 (-1935 2510);
PAINT MONO (-1935 2510);
FORCEPROP 0 LASTPIN (-1925 2550) $PN 169
J 2
(-1935 2560);
DISPLAY 0.680851 (-1935 2560);
PAINT MONO (-1935 2560);
FORCEPROP 0 LASTPIN (-1925 2600) $PN 171
J 2
(-1935 2610);
DISPLAY 0.680851 (-1935 2610);
PAINT MONO (-1935 2610);
FORCEPROP 0 LASTPIN (-1925 2650) $PN 173
J 2
(-1935 2660);
DISPLAY 0.680851 (-1935 2660);
PAINT MONO (-1935 2660);
FORCEPROP 0 LASTPIN (-1925 2700) $PN 175
J 2
(-1935 2710);
DISPLAY 0.680851 (-1935 2710);
PAINT MONO (-1935 2710);
FORCEPROP 0 LASTPIN (-1925 2750) $PN 177
J 2
(-1935 2760);
DISPLAY 0.680851 (-1935 2760);
PAINT MONO (-1935 2760);
FORCEPROP 0 LASTPIN (-1925 2800) $PN 180
J 2
(-1935 2810);
DISPLAY 0.680851 (-1935 2810);
PAINT MONO (-1935 2810);
FORCEPROP 0 LASTPIN (-1925 2850) $PN 182
J 2
(-1935 2860);
DISPLAY 0.680851 (-1935 2860);
PAINT MONO (-1935 2860);
FORCEPROP 0 LASTPIN (-1925 2900) $PN 184
J 2
(-1935 2910);
DISPLAY 0.680851 (-1935 2910);
PAINT MONO (-1935 2910);
FORCEPROP 0 LASTPIN (-1925 2950) $PN 186
J 2
(-1935 2960);
DISPLAY 0.680851 (-1935 2960);
PAINT MONO (-1935 2960);
FORCEPROP 0 LASTPIN (-1925 3000) $PN 188
J 2
(-1935 3010);
DISPLAY 0.680851 (-1935 3010);
PAINT MONO (-1935 3010);
FORCEPROP 0 LASTPIN (-1925 3050) $PN 191
J 2
(-1935 3060);
DISPLAY 0.680851 (-1935 3060);
PAINT MONO (-1935 3060);
FORCEPROP 0 LASTPIN (-1925 3100) $PN 193
J 2
(-1935 3110);
DISPLAY 0.680851 (-1935 3110);
PAINT MONO (-1935 3110);
FORCEPROP 0 LASTPIN (-1925 3150) $PN 195
J 2
(-1935 3160);
DISPLAY 0.680851 (-1935 3160);
PAINT MONO (-1935 3160);
FORCEPROP 0 LASTPIN (-1925 3200) $PN 197
J 2
(-1935 3210);
DISPLAY 0.680851 (-1935 3210);
PAINT MONO (-1935 3210);
FORCEPROP 0 LASTPIN (-1925 3250) $PN 199
J 2
(-1935 3260);
DISPLAY 0.680851 (-1935 3260);
PAINT MONO (-1935 3260);
FORCEPROP 0 LASTPIN (-1925 3300) $PN 202
J 2
(-1935 3310);
DISPLAY 0.680851 (-1935 3310);
PAINT MONO (-1935 3310);
FORCEPROP 0 LASTPIN (-1925 3350) $PN 204
J 2
(-1935 3360);
DISPLAY 0.680851 (-1935 3360);
PAINT MONO (-1935 3360);
FORCEPROP 0 LASTPIN (-1925 3400) $PN 206
J 2
(-1935 3410);
DISPLAY 0.680851 (-1935 3410);
PAINT MONO (-1935 3410);
FORCEPROP 0 LASTPIN (-1925 3450) $PN 208
J 2
(-1935 3460);
DISPLAY 0.680851 (-1935 3460);
PAINT MONO (-1935 3460);
FORCEPROP 0 LASTPIN (-1925 3500) $PN 210
J 2
(-1935 3510);
DISPLAY 0.680851 (-1935 3510);
PAINT MONO (-1935 3510);
FORCEPROP 0 LASTPIN (-1925 3550) $PN 212
J 2
(-1935 3560);
DISPLAY 0.680851 (-1935 3560);
PAINT MONO (-1935 3560);
FORCEPROP 0 LASTPIN (-1925 3600) $PN 214
J 2
(-1935 3610);
DISPLAY 0.680851 (-1935 3610);
PAINT MONO (-1935 3610);
FORCEPROP 0 LASTPIN (-1925 3650) $PN 216
J 2
(-1935 3660);
DISPLAY 0.680851 (-1935 3660);
PAINT MONO (-1935 3660);
FORCEPROP 0 LASTPIN (-1925 3700) $PN 219
J 2
(-1935 3710);
DISPLAY 0.680851 (-1935 3710);
PAINT MONO (-1935 3710);
FORCEPROP 0 LASTPIN (-1925 3750) $PN 222
J 2
(-1935 3760);
DISPLAY 0.680851 (-1935 3760);
PAINT MONO (-1935 3760);
FORCEPROP 0 LASTPIN (-1925 3800) $PN 224
J 2
(-1935 3810);
DISPLAY 0.680851 (-1935 3810);
PAINT MONO (-1935 3810);
FORCEPROP 0 LASTPIN (-1925 3850) $PN 226
J 2
(-1935 3860);
DISPLAY 0.680851 (-1935 3860);
PAINT MONO (-1935 3860);
FORCEPROP 0 LASTPIN (-1925 3900) $PN 228
J 2
(-1935 3910);
DISPLAY 0.680851 (-1935 3910);
PAINT MONO (-1935 3910);
FORCEPROP 0 LASTPIN (-1925 3950) $PN 230
J 2
(-1935 3960);
DISPLAY 0.680851 (-1935 3960);
PAINT MONO (-1935 3960);
FORCEPROP 0 LASTPIN (-1925 4000) $PN 233
J 2
(-1935 4010);
DISPLAY 0.680851 (-1935 4010);
PAINT MONO (-1935 4010);
FORCEPROP 0 LASTPIN (-1925 4050) $PN 235
J 2
(-1935 4060);
DISPLAY 0.680851 (-1935 4060);
PAINT MONO (-1935 4060);
FORCEPROP 0 LASTPIN (-1925 4100) $PN 237
J 2
(-1935 4110);
DISPLAY 0.680851 (-1935 4110);
PAINT MONO (-1935 4110);
FORCEPROP 0 LASTPIN (-1925 4150) $PN 240
J 2
(-1935 4160);
DISPLAY 0.680851 (-1935 4160);
PAINT MONO (-1935 4160);
FORCEPROP 0 LASTPIN (-1925 4200) $PN 242
J 2
(-1935 4210);
DISPLAY 0.680851 (-1935 4210);
PAINT MONO (-1935 4210);
FORCEPROP 0 LASTPIN (-1925 4250) $PN 244
J 2
(-1935 4260);
DISPLAY 0.680851 (-1935 4260);
PAINT MONO (-1935 4260);
FORCEPROP 0 LASTPIN (-1925 4300) $PN 246
J 2
(-1935 4310);
DISPLAY 0.680851 (-1935 4310);
PAINT MONO (-1935 4310);
FORCEPROP 0 LASTPIN (-1925 4350) $PN 248
J 2
(-1935 4360);
DISPLAY 0.680851 (-1935 4360);
PAINT MONO (-1935 4360);
FORCEPROP 0 LASTPIN (-1925 4400) $PN 251
J 2
(-1935 4410);
DISPLAY 0.680851 (-1935 4410);
PAINT MONO (-1935 4410);
FORCEPROP 0 LASTPIN (-1925 4450) $PN 253
J 2
(-1935 4460);
DISPLAY 0.680851 (-1935 4460);
PAINT MONO (-1935 4460);
FORCEPROP 0 LASTPIN (-1925 4500) $PN 255
J 2
(-1935 4510);
DISPLAY 0.680851 (-1935 4510);
PAINT MONO (-1935 4510);
FORCEPROP 0 LASTPIN (-1925 4550) $PN 257
J 2
(-1935 4560);
DISPLAY 0.680851 (-1935 4560);
PAINT MONO (-1935 4560);
FORCEPROP 0 LASTPIN (-1925 4600) $PN 259
J 2
(-1935 4610);
DISPLAY 0.680851 (-1935 4610);
PAINT MONO (-1935 4610);
FORCEPROP 0 LASTPIN (-1925 4650) $PN 262
J 2
(-1935 4660);
DISPLAY 0.680851 (-1935 4660);
PAINT MONO (-1935 4660);
FORCEPROP 0 LASTPIN (-1925 4700) $PN 264
J 2
(-1935 4710);
DISPLAY 0.680851 (-1935 4710);
PAINT MONO (-1935 4710);
FORCEPROP 0 LASTPIN (-1925 4750) $PN 266
J 2
(-1935 4760);
DISPLAY 0.680851 (-1935 4760);
PAINT MONO (-1935 4760);
FORCEPROP 0 LASTPIN (-1925 4800) $PN 268
J 2
(-1935 4810);
DISPLAY 0.680851 (-1935 4810);
PAINT MONO (-1935 4810);
FORCEPROP 0 LASTPIN (-1925 4850) $PN 270
J 2
(-1935 4860);
DISPLAY 0.680851 (-1935 4860);
PAINT MONO (-1935 4860);
FORCEPROP 0 LASTPIN (-1925 4900) $PN 273
J 2
(-1935 4910);
DISPLAY 0.680851 (-1935 4910);
PAINT MONO (-1935 4910);
FORCEPROP 0 LASTPIN (-1925 4950) $PN 275
J 2
(-1935 4960);
DISPLAY 0.680851 (-1935 4960);
PAINT MONO (-1935 4960);
FORCEPROP 0 LASTPIN (-1925 5000) $PN 277
J 2
(-1935 5010);
DISPLAY 0.680851 (-1935 5010);
PAINT MONO (-1935 5010);
FORCEPROP 0 LASTPIN (-1925 5050) $PN 279
J 2
(-1935 5060);
DISPLAY 0.680851 (-1935 5060);
PAINT MONO (-1935 5060);
FORCEPROP 0 LASTPIN (-1925 5100) $PN 281
J 2
(-1935 5110);
DISPLAY 0.680851 (-1935 5110);
PAINT MONO (-1935 5110);
FORCEPROP 0 LASTPIN (-1925 5150) $PN 284
J 2
(-1935 5160);
DISPLAY 0.680851 (-1935 5160);
PAINT MONO (-1935 5160);
FORCEPROP 0 LASTPIN (-1925 5200) $PN 286
J 2
(-1935 5210);
DISPLAY 0.680851 (-1935 5210);
PAINT MONO (-1935 5210);
FORCEPROP 0 LASTPIN (-1925 5250) $PN 288
J 2
(-1935 5260);
DISPLAY 0.680851 (-1935 5260);
PAINT MONO (-1935 5260);
FORCEPROP 1 LAST MATERIAL IO
J 0
(-1775 5575);
DISPLAY 0.468085 (-1775 5575);
PAINT SKYBLUE (-1775 5575);
FORCEPROP 2 LAST PART_TYPE SMLF
J 0
(-1775 5825);
DISPLAY 1.021277 (-1775 5825);
FORCEPROP 2 LAST VALUE SCONN288_DDR506112002KQ
J 0
(-1775 5775);
DISPLAY 0.489362 (-1775 5775);
PAINT SKYBLUE (-1775 5775);
FORCEPROP 1 LAST PART_NUMBER DFHST8FS479
J 0
(-1775 5650);
DISPLAY 0.468085 (-1775 5650);
PAINT SKYBLUE (-1775 5650);
FORCEPROP 1 LAST CDS_LMAN_SYM_OUTLINE -450,1800,450,-1750
J 0
(-1325 3750);
DISPLAY 0.468085 (-1325 3750);
PAINT GREEN (-1325 3750);
DISPLAY INVISIBLE (-1325 3750);
FORCEPROP 1 LAST PATH I155
J 0
(-1325 3750);
DISPLAY 0.723404 (-1325 3750);
PAINT GREEN (-1325 3750);
DISPLAY INVISIBLE (-1325 3750);
FORCEPROP 1 LAST NEEDS_NO_SIZE TRUE
J 0
(-1325 3750);
DISPLAY 0.723404 (-1325 3750);
PAINT GREEN (-1325 3750);
DISPLAY INVISIBLE (-1325 3750);
FORCEPROP 2 LAST CDS_LIB pure_quanta
J 0
(-1325 3750);
DISPLAY INVISIBLE (-1325 3750);
FORCEADD GND..1
(-425 1800);
FORCEPROP 3 LASTPIN (-425 1850) SIG_NAME GND\g
J 0
(-415 1860);
DISPLAY 0.659574 (-415 1860);
PAINT MONO (-415 1860);
DISPLAY INVISIBLE (-415 1860);
FORCEPROP 1 LAST SIZE 1B
J 0
(-350 1750);
DISPLAY 0.851064 (-350 1750);
PAINT GREEN (-350 1750);
DISPLAY INVISIBLE (-350 1750);
FORCEPROP 2 LAST CDS_LIB mstr_symbols
J 0
(-425 1800);
DISPLAY 0.723404 (-425 1800);
DISPLAY INVISIBLE (-425 1800);
FORCEPROP 1 LAST BODY_TYPE PLUMBING
J 0
(-470 1757);
DISPLAY 0.340426 (-470 1757);
PAINT GREEN (-470 1757);
DISPLAY INVISIBLE (-470 1757);
FORCEPROP 1 LAST PATH I156
J 0
(-350 1800);
DISPLAY 0.872340 (-350 1800);
PAINT AQUA (-350 1800);
DISPLAY INVISIBLE (-350 1800);
FORCEPROP 1 LAST VOLTAGE 0.0
J 0
(-470 1757);
DISPLAY 0.723404 (-470 1757);
PAINT SKYBLUE (-470 1757);
DISPLAY INVISIBLE (-470 1757);
FORCEPROP 1 LAST HDL_POWER GND
J 0
(-425 1950);
DISPLAY 0.851064 (-425 1950);
PAINT GREEN (-425 1950);
DISPLAY INVISIBLE (-425 1950);
FORCEADD OFFPAGE..1
(-8500 4550);
FORCEPROP 2 LAST $XR0 39 
J 0
(-8721 4550);
DISPLAY 0.638298 (-8721 4550);
PAINT MONO (-8721 4550);
FORCEPROP 2 LAST PATH I16
J 0
(-8700 4600);
DISPLAY 1.021277 (-8700 4600);
DISPLAY INVISIBLE (-8700 4600);
FORCEPROP 1 LAST COMMENT_BODY TRUE
J 0
(-8375 4450);
DISPLAY 0.872340 (-8375 4450);
PAINT GREEN (-8375 4450);
DISPLAY INVISIBLE (-8375 4450);
FORCEPROP 1 LAST OFFPAGE TRUE
J 0
(-8175 4425);
DISPLAY 0.872340 (-8175 4425);
PAINT GREEN (-8175 4425);
DISPLAY INVISIBLE (-8175 4425);
FORCEPROP 2 LAST CDS_LIB mstr_standard
J 0
(-8500 4550);
DISPLAY 0.808511 (-8500 4550);
DISPLAY INVISIBLE (-8500 4550);
FORCEADD OFFPAGE..1
(-8500 4450);
FORCEPROP 2 LAST $XR0 39 
J 0
(-8721 4450);
DISPLAY 0.638298 (-8721 4450);
PAINT MONO (-8721 4450);
FORCEPROP 2 LAST PATH I17
J 0
(-8700 4500);
DISPLAY 1.021277 (-8700 4500);
DISPLAY INVISIBLE (-8700 4500);
FORCEPROP 1 LAST COMMENT_BODY TRUE
J 0
(-8375 4350);
DISPLAY 0.872340 (-8375 4350);
PAINT GREEN (-8375 4350);
DISPLAY INVISIBLE (-8375 4350);
FORCEPROP 1 LAST OFFPAGE TRUE
J 0
(-8175 4325);
DISPLAY 0.872340 (-8175 4325);
PAINT GREEN (-8175 4325);
DISPLAY INVISIBLE (-8175 4325);
FORCEPROP 2 LAST CDS_LIB mstr_standard
J 0
(-8500 4450);
DISPLAY 0.723404 (-8500 4450);
PAINT MONO (-8500 4450);
DISPLAY INVISIBLE (-8500 4450);
FORCEADD OFFPAGE..6
(-8500 2850);
FORCEPROP 2 LAST $XR5 136 
J 0
(-9349 2850);
DISPLAY 0.638298 (-9349 2850);
PAINT MONO (-9349 2850);
FORCEPROP 2 LAST $XR4 102 
J 0
(-9229 2850);
DISPLAY 0.638298 (-9229 2850);
PAINT MONO (-9229 2850);
FORCEPROP 2 LAST $XR3 101 
J 0
(-9109 2850);
DISPLAY 0.638298 (-9109 2850);
PAINT MONO (-9109 2850);
FORCEPROP 2 LAST $XR2 100 
J 0
(-8989 2850);
DISPLAY 0.638298 (-8989 2850);
PAINT MONO (-8989 2850);
FORCEPROP 2 LAST $XR1 98 
J 0
(-8869 2850);
DISPLAY 0.638298 (-8869 2850);
PAINT MONO (-8869 2850);
FORCEPROP 2 LAST $XR0 97 
J 0
(-8779 2850);
DISPLAY 0.638298 (-8779 2850);
PAINT MONO (-8779 2850);
FORCEPROP 2 LAST PATH I179
J 0
(-8775 2900);
DISPLAY 1.021277 (-8775 2900);
DISPLAY INVISIBLE (-8775 2900);
FORCEPROP 1 LAST COMMENT_BODY TRUE
J 0
(-8400 2775);
DISPLAY 0.872340 (-8400 2775);
PAINT GREEN (-8400 2775);
DISPLAY INVISIBLE (-8400 2775);
FORCEPROP 1 LAST OFFPAGE TRUE
J 0
(-8175 2725);
DISPLAY 0.872340 (-8175 2725);
PAINT GREEN (-8175 2725);
DISPLAY INVISIBLE (-8175 2725);
FORCEPROP 2 LAST CDS_LIB mstr_standard
J 0
(-8500 2850);
DISPLAY 0.808511 (-8500 2850);
DISPLAY INVISIBLE (-8500 2850);
FORCEADD OFFPAGE..1
(-8500 4400);
FORCEPROP 2 LAST $XR0 39 
J 0
(-8721 4400);
DISPLAY 0.638298 (-8721 4400);
PAINT MONO (-8721 4400);
FORCEPROP 2 LAST PATH I18
J 0
(-8700 4450);
DISPLAY 1.021277 (-8700 4450);
DISPLAY INVISIBLE (-8700 4450);
FORCEPROP 1 LAST COMMENT_BODY TRUE
J 0
(-8375 4300);
DISPLAY 0.872340 (-8375 4300);
PAINT GREEN (-8375 4300);
DISPLAY INVISIBLE (-8375 4300);
FORCEPROP 1 LAST OFFPAGE TRUE
J 0
(-8175 4275);
DISPLAY 0.872340 (-8175 4275);
PAINT GREEN (-8175 4275);
DISPLAY INVISIBLE (-8175 4275);
FORCEPROP 2 LAST CDS_LIB mstr_standard
J 0
(-8500 4400);
DISPLAY 0.808511 (-8500 4400);
DISPLAY INVISIBLE (-8500 4400);
FORCEADD Q_CAP..1
R 2
(-8775 3225);
FORCEPROP 1 LAST LOCATION C144
J 2
(-8825 3325);
DISPLAY 0.489362 (-8825 3325);
PAINT SKYBLUE (-8825 3325);
FORCEPROP 0 LAST $SEC 1
J 0
(-8825 3375);
DISPLAY 0.680851 (-8825 3375);
PAINT MONO (-8825 3375);
DISPLAY INVISIBLE (-8825 3375);
FORCEPROP 0 LAST CDS_SEC 1
J 0
(-8825 3375);
DISPLAY 1.021277 (-8825 3375);
DISPLAY INVISIBLE (-8825 3375);
FORCEPROP 1 LASTPIN (-8775 3325) $PN 1
J 2
(-8785 3305);
DISPLAY 0.489362 (-8785 3305);
PAINT MONO (-8785 3305);
FORCEPROP 1 LASTPIN (-8775 3125) $PN 2
J 2
(-8785 3105);
DISPLAY 0.489362 (-8785 3105);
PAINT MONO (-8785 3105);
FORCEPROP 1 LAST MATERIAL X7R
J 2
(-8825 3125);
DISPLAY 0.489362 (-8825 3125);
PAINT SKYBLUE (-8825 3125);
FORCEPROP 1 LAST TOLERANCE 10%
J 2
(-8825 3175);
DISPLAY 0.489362 (-8825 3175);
PAINT SKYBLUE (-8825 3175);
FORCEPROP 1 LAST VALUE 0.1UF
J 2
(-8825 3275);
DISPLAY 0.489362 (-8825 3275);
PAINT SKYBLUE (-8825 3275);
FORCEPROP 1 LAST PART_NUMBER CH4104K1B00
J 2
(-8825 3075);
DISPLAY 0.489362 (-8825 3075);
PAINT SKYBLUE (-8825 3075);
FORCEPROP 1 LAST VOLTAGE 25V
J 2
(-8825 3225);
DISPLAY 0.489362 (-8825 3225);
PAINT SKYBLUE (-8825 3225);
FORCEPROP 1 LAST PACK_TYPE 0402
J 2
(-8825 3025);
DISPLAY 0.489362 (-8825 3025);
PAINT SKYBLUE (-8825 3025);
FORCEPROP 0 LAST BOM_COST MEM
J 2
(-8830 3370);
DISPLAY 0.595745 (-8830 3370);
PAINT MONO (-8830 3370);
DISPLAY INVISIBLE (-8830 3370);
FORCEPROP 2 LAST CDS_LIB pure_quanta
J 0
(-8775 3225);
DISPLAY INVISIBLE (-8775 3225);
FORCEPROP 1 LAST PATH I185
J 2
(-8825 3375);
DISPLAY 0.978723 (-8825 3375);
PAINT WHITE (-8825 3375);
DISPLAY INVISIBLE (-8825 3375);
FORCEPROP 0 LAST ROOM MEM_CH_A_CPU0_DIMM1
J 2
(-8830 3370);
DISPLAY 0.595745 (-8830 3370);
PAINT RED (-8830 3370);
DISPLAY INVISIBLE (-8830 3370);
FORCEADD GND..1
(-8775 3000);
FORCEPROP 3 LASTPIN (-8775 3050) SIG_NAME GND\g
J 0
(-8765 3060);
DISPLAY 0.659574 (-8765 3060);
PAINT MONO (-8765 3060);
DISPLAY INVISIBLE (-8765 3060);
FORCEPROP 2 LAST BOM_COST MEM
J 0
(-8750 3125);
DISPLAY 0.659574 (-8750 3125);
DISPLAY INVISIBLE (-8750 3125);
FORCEPROP 1 LAST SIZE 1B
J 0
(-8700 2950);
DISPLAY 0.723404 (-8700 2950);
PAINT GREEN (-8700 2950);
DISPLAY INVISIBLE (-8700 2950);
FORCEPROP 2 LAST CDS_LIB mstr_symbols
J 0
(-8775 3000);
DISPLAY 0.808511 (-8775 3000);
DISPLAY INVISIBLE (-8775 3000);
FORCEPROP 1 LAST BODY_TYPE PLUMBING
J 0
(-8820 2957);
DISPLAY 0.276596 (-8820 2957);
PAINT GREEN (-8820 2957);
DISPLAY INVISIBLE (-8820 2957);
FORCEPROP 1 LAST PATH I186
J 0
(-8700 3000);
DISPLAY 0.872340 (-8700 3000);
PAINT AQUA (-8700 3000);
DISPLAY INVISIBLE (-8700 3000);
FORCEPROP 1 LAST VOLTAGE 0
J 0
(-8795 3095);
DISPLAY 0.829787 (-8795 3095);
PAINT SKYBLUE (-8795 3095);
DISPLAY INVISIBLE (-8795 3095);
FORCEPROP 2 LAST ROOM MEM_EFGH_DECOUPLING_CAPS
J 0
(-8750 3075);
DISPLAY 0.659574 (-8750 3075);
PAINT RED (-8750 3075);
DISPLAY INVISIBLE (-8750 3075);
FORCEPROP 1 LAST HDL_POWER GND
J 0
(-8775 3150);
DISPLAY 0.723404 (-8775 3150);
PAINT GREEN (-8775 3150);
DISPLAY INVISIBLE (-8775 3150);
FORCEADD OFFPAGE..6
(-9200 2150);
FORCEPROP 2 LAST $XR5 81 
J 0
(-9539 2186);
DISPLAY 0.638298 (-9539 2186);
PAINT MONO (-9539 2186);
FORCEPROP 2 LAST $XR4 102 
J 0
(-9449 2258);
DISPLAY 0.638298 (-9449 2258);
PAINT MONO (-9449 2258);
FORCEPROP 2 LAST $XR3 101 
J 0
(-9449 2222);
DISPLAY 0.638298 (-9449 2222);
PAINT MONO (-9449 2222);
FORCEPROP 2 LAST $XR2 100 
J 0
(-9449 2186);
DISPLAY 0.638298 (-9449 2186);
PAINT MONO (-9449 2186);
FORCEPROP 2 LAST $XR1 98 
J 0
(-9539 2150);
DISPLAY 0.638298 (-9539 2150);
PAINT MONO (-9539 2150);
FORCEPROP 2 LAST $XR0 97 
J 0
(-9449 2150);
DISPLAY 0.638298 (-9449 2150);
PAINT MONO (-9449 2150);
FORCEPROP 2 LAST PATH I187
J 0
(-9150 2225);
DISPLAY 1.021277 (-9150 2225);
DISPLAY INVISIBLE (-9150 2225);
FORCEPROP 1 LAST COMMENT_BODY TRUE
J 0
(-9100 2075);
DISPLAY 0.872340 (-9100 2075);
PAINT GREEN (-9100 2075);
DISPLAY INVISIBLE (-9100 2075);
FORCEPROP 1 LAST OFFPAGE TRUE
J 0
(-8875 2025);
DISPLAY 0.872340 (-8875 2025);
PAINT GREEN (-8875 2025);
DISPLAY INVISIBLE (-8875 2025);
FORCEPROP 2 LAST CDS_LIB mstr_standard
J 0
(-9200 2150);
DISPLAY 0.808511 (-9200 2150);
DISPLAY INVISIBLE (-9200 2150);
FORCEADD Q_RES..1
R 2
(-8700 2150);
FORCEPROP 1 LAST LOCATION R305
J 2
(-8675 2175);
DISPLAY 0.489362 (-8675 2175);
PAINT SKYBLUE (-8675 2175);
FORCEPROP 0 LAST $SEC 1
J 0
(-8675 2225);
DISPLAY 0.680851 (-8675 2225);
PAINT MONO (-8675 2225);
DISPLAY INVISIBLE (-8675 2225);
FORCEPROP 0 LAST CDS_SEC 1
J 0
(-8675 2225);
DISPLAY 1.021277 (-8675 2225);
DISPLAY INVISIBLE (-8675 2225);
FORCEPROP 1 LASTPIN (-8600 2150) $PN 1
J 2
(-8612 2162);
DISPLAY 0.489362 (-8612 2162);
PAINT MONO (-8612 2162);
FORCEPROP 1 LASTPIN (-8800 2150) $PN 2
J 2
(-8762 2162);
DISPLAY 0.489362 (-8762 2162);
PAINT MONO (-8762 2162);
FORCEPROP 1 LAST VALUE 0
J 0
(-8700 2100);
DISPLAY 0.489362 (-8700 2100);
PAINT SKYBLUE (-8700 2100);
FORCEPROP 2 LAST BOM_COST MEM
J 0
(-8725 2300);
DISPLAY 0.744681 (-8725 2300);
PAINT WHITE (-8725 2300);
DISPLAY INVISIBLE (-8725 2300);
FORCEPROP 2 LAST CDS_LIB pure_quanta
J 0
(-8700 2150);
DISPLAY INVISIBLE (-8700 2150);
FORCEPROP 1 LAST PATH I188
J 2
(-8650 2300);
DISPLAY 0.978723 (-8650 2300);
PAINT WHITE (-8650 2300);
DISPLAY INVISIBLE (-8650 2300);
FORCEPROP 1 LAST WATTAGE 1/16W
J 0
(-8625 2075);
DISPLAY 0.489362 (-8625 2075);
PAINT SKYBLUE (-8625 2075);
DISPLAY INVISIBLE (-8625 2075);
FORCEPROP 1 LAST MATERIAL CHIP
J 0
(-8875 2125);
DISPLAY 0.489362 (-8875 2125);
PAINT SKYBLUE (-8875 2125);
DISPLAY INVISIBLE (-8875 2125);
FORCEPROP 1 LAST TOLERANCE 5%
J 2
(-8575 2125);
DISPLAY 0.489362 (-8575 2125);
PAINT SKYBLUE (-8575 2125);
DISPLAY INVISIBLE (-8575 2125);
FORCEPROP 1 LAST PART_NUMBER CS00002JB38
J 0
(-8800 2200);
DISPLAY 0.489362 (-8800 2200);
PAINT SKYBLUE (-8800 2200);
DISPLAY INVISIBLE (-8800 2200);
FORCEPROP 1 LAST PACK_TYPE 0402LF
J 0
(-8875 2075);
DISPLAY 0.489362 (-8875 2075);
PAINT SKYBLUE (-8875 2075);
DISPLAY INVISIBLE (-8875 2075);
FORCEPROP 2 LAST ROOM RST_CPU0_PLD_TO_DIMM
J 0
(-8725 2250);
DISPLAY 0.744681 (-8725 2250);
PAINT RED (-8725 2250);
DISPLAY INVISIBLE (-8725 2250);
FORCEADD VCC_CORE..1
(-8575 2475);
FORCEPROP 3 LASTPIN (-8575 2425) SIG_NAME P3V3_STBY\g
J 0
(-8565 2435);
DISPLAY 0.659574 (-8565 2435);
PAINT MONO (-8565 2435);
DISPLAY INVISIBLE (-8565 2435);
FORCEPROP 1 LAST HDL_POWER P3V3_STBY
J 1
(-8575 2525);
DISPLAY 0.489362 (-8575 2525);
PAINT GREEN (-8575 2525);
FORCEPROP 2 LAST CDS_LIB mstr_symbols
J 0
(-8575 2475);
DISPLAY INVISIBLE (-8575 2475);
FORCEPROP 1 LAST PATH I189
J 0
(-8525 2500);
DISPLAY 0.872340 (-8525 2500);
PAINT AQUA (-8525 2500);
DISPLAY INVISIBLE (-8525 2500);
FORCEPROP 0 LAST VOLTAGE 3.3
J 0
(-8850 2625);
DISPLAY 1.021277 (-8850 2625);
PAINT SKYBLUE (-8850 2625);
DISPLAY INVISIBLE (-8850 2625);
FORCEPROP 2 LAST ROOM PVCCINFAON_CPU0_CTRL
J 0
(-8575 2575);
DISPLAY 0.808511 (-8575 2575);
PAINT RED (-8575 2575);
DISPLAY INVISIBLE (-8575 2575);
FORCEADD OFFPAGE..1
(-8500 4600);
FORCEPROP 2 LAST $XR0 39 
J 0
(-8721 4600);
DISPLAY 0.638298 (-8721 4600);
PAINT MONO (-8721 4600);
FORCEPROP 2 LAST PATH I19
J 0
(-8700 4650);
DISPLAY 1.021277 (-8700 4650);
DISPLAY INVISIBLE (-8700 4650);
FORCEPROP 1 LAST COMMENT_BODY TRUE
J 0
(-8375 4500);
DISPLAY 0.872340 (-8375 4500);
PAINT GREEN (-8375 4500);
DISPLAY INVISIBLE (-8375 4500);
FORCEPROP 1 LAST OFFPAGE TRUE
J 0
(-8175 4475);
DISPLAY 0.872340 (-8175 4475);
PAINT GREEN (-8175 4475);
DISPLAY INVISIBLE (-8175 4475);
FORCEPROP 2 LAST CDS_LIB mstr_standard
J 0
(-8500 4600);
DISPLAY 0.723404 (-8500 4600);
PAINT MONO (-8500 4600);
DISPLAY INVISIBLE (-8500 4600);
FORCEADD Q_RES..2
(-8575 2300);
FORCEPROP 1 LAST LOCATION R105
J 0
(-8530 2425);
DISPLAY 0.489362 (-8530 2425);
PAINT SKYBLUE (-8530 2425);
FORCEPROP 0 LAST $SEC 1
J 0
(-8525 2475);
DISPLAY 0.680851 (-8525 2475);
PAINT MONO (-8525 2475);
DISPLAY INVISIBLE (-8525 2475);
FORCEPROP 0 LAST CDS_SEC 1
J 0
(-8525 2475);
DISPLAY 1.021277 (-8525 2475);
DISPLAY INVISIBLE (-8525 2475);
FORCEPROP 1 LASTPIN (-8575 2400) $PN 1
J 0
(-8570 2362);
DISPLAY 0.489362 (-8570 2362);
PAINT MONO (-8570 2362);
FORCEPROP 1 LASTPIN (-8575 2200) $PN 2
J 0
(-8570 2210);
DISPLAY 0.489362 (-8570 2210);
PAINT MONO (-8570 2210);
FORCEPROP 1 LAST MATERIAL EMPTY
J 0
(-8525 2300);
DISPLAY 0.489362 (-8525 2300);
PAINT RED (-8525 2300);
FORCEPROP 1 LAST PACK_TYPE 0402LF
J 0
(-8525 2250);
DISPLAY 0.489362 (-8525 2250);
PAINT SKYBLUE (-8525 2250);
FORCEPROP 1 LAST WATTAGE 1/16W
J 0
(-8525 2325);
DISPLAY 0.489362 (-8525 2325);
PAINT SKYBLUE (-8525 2325);
FORCEPROP 1 LAST TOLERANCE 5%
J 0
(-8525 2350);
DISPLAY 0.489362 (-8525 2350);
PAINT SKYBLUE (-8525 2350);
FORCEPROP 1 LAST VALUE 1K
J 0
(-8530 2375);
DISPLAY 0.489362 (-8530 2375);
PAINT SKYBLUE (-8530 2375);
FORCEPROP 2 LAST CDS_LIB pure_quanta
J 2
(-8575 2300);
DISPLAY INVISIBLE (-8575 2300);
FORCEPROP 2 LAST BOM_COST MEM
J 0
(-8525 2475);
DISPLAY 0.808511 (-8525 2475);
DISPLAY INVISIBLE (-8525 2475);
FORCEPROP 1 LAST PATH I190
J 0
(-8525 2475);
DISPLAY 0.978723 (-8525 2475);
PAINT WHITE (-8525 2475);
DISPLAY INVISIBLE (-8525 2475);
FORCEPROP 1 LAST PART_NUMBER TMP_QCS21002JB34
J 0
(-8525 2275);
DISPLAY 0.489362 (-8525 2275);
PAINT SKYBLUE (-8525 2275);
DISPLAY INVISIBLE (-8525 2275);
FORCEPROP 2 LAST ROOM MEM_CH_A_CPU0_DIMM1
J 0
(-8525 2525);
DISPLAY 0.808511 (-8525 2525);
PAINT RED (-8525 2525);
DISPLAY INVISIBLE (-8525 2525);
FORCEADD TAP..1
(-3550 3750);
FORCEPROP 3 LASTPIN (-3600 3750) SIG_NAME M_C_CPU1_SA_DQS_DP<1>
J 0
(-3590 3760);
DISPLAY 0.659574 (-3590 3760);
PAINT MONO (-3590 3760);
DISPLAY INVISIBLE (-3590 3760);
FORCEPROP 1 LASTPIN (-3600 3750) BN 1
J 0
(-3612 3758);
DISPLAY 0.489362 (-3612 3758);
PAINT GREEN (-3612 3758);
FORCEPROP 2 LAST CDS_LIB mstr_standard
J 0
(-3550 3750);
DISPLAY 0.723404 (-3550 3750);
PAINT MONO (-3550 3750);
DISPLAY INVISIBLE (-3550 3750);
FORCEPROP 1 LAST BODY_TYPE PLUMBING
J 0
(-3550 3800);
DISPLAY 0.872340 (-3550 3800);
PAINT GREEN (-3550 3800);
DISPLAY INVISIBLE (-3550 3800);
FORCEPROP 1 LAST HDL_TAP TRUE
J 0
(-3225 3625);
DISPLAY 0.872340 (-3225 3625);
DISPLAY INVISIBLE (-3225 3625);
FORCEPROP 1 LAST PATH I191
J 0
(-3552 3750);
DISPLAY 0.872340 (-3552 3750);
PAINT GREEN (-3552 3750);
DISPLAY INVISIBLE (-3552 3750);
FORCEADD TAP..1
(-3550 3850);
FORCEPROP 3 LASTPIN (-3600 3850) SIG_NAME M_C_CPU1_SA_DQS_DP<2>
J 0
(-3590 3860);
DISPLAY 0.659574 (-3590 3860);
PAINT MONO (-3590 3860);
DISPLAY INVISIBLE (-3590 3860);
FORCEPROP 1 LASTPIN (-3600 3850) BN 2
J 0
(-3612 3858);
DISPLAY 0.489362 (-3612 3858);
PAINT GREEN (-3612 3858);
FORCEPROP 2 LAST CDS_LIB mstr_standard
J 0
(-3550 3850);
DISPLAY 0.723404 (-3550 3850);
PAINT MONO (-3550 3850);
DISPLAY INVISIBLE (-3550 3850);
FORCEPROP 1 LAST BODY_TYPE PLUMBING
J 0
(-3550 3900);
DISPLAY 0.872340 (-3550 3900);
PAINT GREEN (-3550 3900);
DISPLAY INVISIBLE (-3550 3900);
FORCEPROP 1 LAST HDL_TAP TRUE
J 0
(-3225 3725);
DISPLAY 0.872340 (-3225 3725);
DISPLAY INVISIBLE (-3225 3725);
FORCEPROP 1 LAST PATH I193
J 0
(-3552 3850);
DISPLAY 0.872340 (-3552 3850);
PAINT GREEN (-3552 3850);
DISPLAY INVISIBLE (-3552 3850);
FORCEADD OFFPAGE..2
(-2550 4600);
FORCEPROP 2 LAST $XR0 39 
J 0
(-2361 4600);
DISPLAY 0.638298 (-2361 4600);
PAINT MONO (-2361 4600);
FORCEPROP 1 LAST COMMENT_BODY TRUE
J 0
(-2595 4505);
DISPLAY 0.872340 (-2595 4505);
PAINT GREEN (-2595 4505);
DISPLAY INVISIBLE (-2595 4505);
FORCEPROP 1 LAST OFFPAGE TRUE
J 0
(-2225 4475);
DISPLAY 0.723404 (-2225 4475);
PAINT GREEN (-2225 4475);
DISPLAY INVISIBLE (-2225 4475);
FORCEPROP 2 LAST CDS_LIB mstr_standard
J 0
(-2550 4600);
DISPLAY 0.723404 (-2550 4600);
PAINT MONO (-2550 4600);
DISPLAY INVISIBLE (-2550 4600);
FORCEPROP 2 LAST PATH I194
J 0
(-2350 4650);
DISPLAY 0.680851 (-2350 4650);
DISPLAY INVISIBLE (-2350 4650);
FORCEADD OFFPAGE..2
(-2550 4550);
FORCEPROP 2 LAST $XR0 39 
J 0
(-2361 4550);
DISPLAY 0.638298 (-2361 4550);
PAINT MONO (-2361 4550);
FORCEPROP 1 LAST COMMENT_BODY TRUE
J 0
(-2595 4455);
DISPLAY 0.872340 (-2595 4455);
PAINT GREEN (-2595 4455);
DISPLAY INVISIBLE (-2595 4455);
FORCEPROP 1 LAST OFFPAGE TRUE
J 0
(-2225 4425);
DISPLAY 0.723404 (-2225 4425);
PAINT GREEN (-2225 4425);
DISPLAY INVISIBLE (-2225 4425);
FORCEPROP 2 LAST CDS_LIB mstr_standard
J 0
(-2550 4550);
DISPLAY 0.723404 (-2550 4550);
PAINT MONO (-2550 4550);
DISPLAY INVISIBLE (-2550 4550);
FORCEPROP 2 LAST PATH I195
J 0
(-2350 4600);
DISPLAY 0.680851 (-2350 4600);
DISPLAY INVISIBLE (-2350 4600);
FORCEADD TAP..1
(-3350 4400);
FORCEPROP 3 LASTPIN (-3400 4400) SIG_NAME M_C_CPU1_SA_DQS_DN<8>
J 0
(-3390 4410);
DISPLAY 0.659574 (-3390 4410);
PAINT MONO (-3390 4410);
DISPLAY INVISIBLE (-3390 4410);
FORCEPROP 1 LASTPIN (-3400 4400) BN 8
J 0
(-3412 4408);
DISPLAY 0.489362 (-3412 4408);
PAINT GREEN (-3412 4408);
FORCEPROP 2 LAST CDS_LIB mstr_standard
J 0
(-3350 4400);
DISPLAY 0.723404 (-3350 4400);
PAINT MONO (-3350 4400);
DISPLAY INVISIBLE (-3350 4400);
FORCEPROP 1 LAST BODY_TYPE PLUMBING
J 0
(-3350 4450);
DISPLAY 0.872340 (-3350 4450);
PAINT GREEN (-3350 4450);
DISPLAY INVISIBLE (-3350 4450);
FORCEPROP 1 LAST HDL_TAP TRUE
J 0
(-3025 4275);
DISPLAY 0.872340 (-3025 4275);
DISPLAY INVISIBLE (-3025 4275);
FORCEPROP 1 LAST PATH I196
J 0
(-3352 4400);
DISPLAY 0.872340 (-3352 4400);
PAINT GREEN (-3352 4400);
DISPLAY INVISIBLE (-3352 4400);
FORCEADD TAP..1
(-3350 4500);
FORCEPROP 3 LASTPIN (-3400 4500) SIG_NAME M_C_CPU1_SA_DQS_DN<9>
J 0
(-3390 4510);
DISPLAY 0.659574 (-3390 4510);
PAINT MONO (-3390 4510);
DISPLAY INVISIBLE (-3390 4510);
FORCEPROP 1 LASTPIN (-3400 4500) BN 9
J 0
(-3412 4508);
DISPLAY 0.489362 (-3412 4508);
PAINT GREEN (-3412 4508);
FORCEPROP 2 LAST CDS_LIB mstr_standard
J 0
(-3350 4500);
DISPLAY 0.723404 (-3350 4500);
PAINT MONO (-3350 4500);
DISPLAY INVISIBLE (-3350 4500);
FORCEPROP 1 LAST BODY_TYPE PLUMBING
J 0
(-3350 4550);
DISPLAY 0.872340 (-3350 4550);
PAINT GREEN (-3350 4550);
DISPLAY INVISIBLE (-3350 4550);
FORCEPROP 1 LAST HDL_TAP TRUE
J 0
(-3025 4375);
DISPLAY 0.872340 (-3025 4375);
DISPLAY INVISIBLE (-3025 4375);
FORCEPROP 1 LAST PATH I197
J 0
(-3352 4500);
DISPLAY 0.872340 (-3352 4500);
PAINT GREEN (-3352 4500);
DISPLAY INVISIBLE (-3352 4500);
FORCEADD TAP..1
(-3550 4450);
FORCEPROP 3 LASTPIN (-3600 4450) SIG_NAME M_C_CPU1_SA_DQS_DP<8>
J 0
(-3590 4460);
DISPLAY 0.659574 (-3590 4460);
PAINT MONO (-3590 4460);
DISPLAY INVISIBLE (-3590 4460);
FORCEPROP 1 LASTPIN (-3600 4450) BN 8
J 0
(-3612 4458);
DISPLAY 0.489362 (-3612 4458);
PAINT GREEN (-3612 4458);
FORCEPROP 2 LAST CDS_LIB mstr_standard
J 0
(-3550 4450);
DISPLAY 0.723404 (-3550 4450);
PAINT MONO (-3550 4450);
DISPLAY INVISIBLE (-3550 4450);
FORCEPROP 1 LAST BODY_TYPE PLUMBING
J 0
(-3550 4500);
DISPLAY 0.872340 (-3550 4500);
PAINT GREEN (-3550 4500);
DISPLAY INVISIBLE (-3550 4500);
FORCEPROP 1 LAST HDL_TAP TRUE
J 0
(-3225 4325);
DISPLAY 0.872340 (-3225 4325);
DISPLAY INVISIBLE (-3225 4325);
FORCEPROP 1 LAST PATH I198
J 0
(-3552 4450);
DISPLAY 0.872340 (-3552 4450);
PAINT GREEN (-3552 4450);
DISPLAY INVISIBLE (-3552 4450);
FORCEADD TAP..1
(-3550 4550);
FORCEPROP 3 LASTPIN (-3600 4550) SIG_NAME M_C_CPU1_SA_DQS_DP<9>
J 0
(-3590 4560);
DISPLAY 0.659574 (-3590 4560);
PAINT MONO (-3590 4560);
DISPLAY INVISIBLE (-3590 4560);
FORCEPROP 1 LASTPIN (-3600 4550) BN 9
J 0
(-3612 4558);
DISPLAY 0.489362 (-3612 4558);
PAINT GREEN (-3612 4558);
FORCEPROP 2 LAST CDS_LIB mstr_standard
J 0
(-3550 4550);
DISPLAY 0.723404 (-3550 4550);
PAINT MONO (-3550 4550);
DISPLAY INVISIBLE (-3550 4550);
FORCEPROP 1 LAST BODY_TYPE PLUMBING
J 0
(-3550 4600);
DISPLAY 0.872340 (-3550 4600);
PAINT GREEN (-3550 4600);
DISPLAY INVISIBLE (-3550 4600);
FORCEPROP 1 LAST HDL_TAP TRUE
J 0
(-3225 4425);
DISPLAY 0.872340 (-3225 4425);
DISPLAY INVISIBLE (-3225 4425);
FORCEPROP 1 LAST PATH I199
J 0
(-3552 4550);
DISPLAY 0.872340 (-3552 4550);
PAINT GREEN (-3552 4550);
DISPLAY INVISIBLE (-3552 4550);
FORCEADD OFFPAGE..5
(-8500 1950);
FORCEPROP 2 LAST $XR0 39 
J 0
(-8754 1950);
DISPLAY 0.638298 (-8754 1950);
PAINT MONO (-8754 1950);
FORCEPROP 2 LAST PATH I2
J 0
(-8750 2000);
DISPLAY 1.021277 (-8750 2000);
DISPLAY INVISIBLE (-8750 2000);
FORCEPROP 1 LAST COMMENT_BODY TRUE
J 0
(-8400 1875);
DISPLAY 0.872340 (-8400 1875);
PAINT GREEN (-8400 1875);
DISPLAY INVISIBLE (-8400 1875);
FORCEPROP 1 LAST OFFPAGE TRUE
J 0
(-8175 1825);
DISPLAY 0.872340 (-8175 1825);
PAINT GREEN (-8175 1825);
DISPLAY INVISIBLE (-8175 1825);
FORCEPROP 2 LAST CDS_LIB mstr_standard
J 0
(-8500 1950);
DISPLAY 0.808511 (-8500 1950);
DISPLAY INVISIBLE (-8500 1950);
FORCEADD OFFPAGE..1
(-8500 5050);
FORCEPROP 2 LAST $XR0 39 
J 0
(-8721 5050);
DISPLAY 0.638298 (-8721 5050);
PAINT MONO (-8721 5050);
FORCEPROP 2 LAST PATH I20
J 0
(-8700 5100);
DISPLAY 1.021277 (-8700 5100);
DISPLAY INVISIBLE (-8700 5100);
FORCEPROP 1 LAST COMMENT_BODY TRUE
J 0
(-8375 4950);
DISPLAY 0.872340 (-8375 4950);
PAINT GREEN (-8375 4950);
DISPLAY INVISIBLE (-8375 4950);
FORCEPROP 1 LAST OFFPAGE TRUE
J 0
(-8175 4925);
DISPLAY 0.872340 (-8175 4925);
PAINT GREEN (-8175 4925);
DISPLAY INVISIBLE (-8175 4925);
FORCEPROP 2 LAST CDS_LIB mstr_standard
J 0
(-8500 5050);
DISPLAY 0.723404 (-8500 5050);
PAINT MONO (-8500 5050);
DISPLAY INVISIBLE (-8500 5050);
FORCEADD TAP..1
(-3550 4350);
FORCEPROP 3 LASTPIN (-3600 4350) SIG_NAME M_C_CPU1_SA_DQS_DP<7>
J 0
(-3590 4360);
DISPLAY 0.659574 (-3590 4360);
PAINT MONO (-3590 4360);
DISPLAY INVISIBLE (-3590 4360);
FORCEPROP 1 LASTPIN (-3600 4350) BN 7
J 0
(-3612 4358);
DISPLAY 0.489362 (-3612 4358);
PAINT GREEN (-3612 4358);
FORCEPROP 2 LAST CDS_LIB mstr_standard
J 0
(-3550 4350);
DISPLAY 0.723404 (-3550 4350);
PAINT MONO (-3550 4350);
DISPLAY INVISIBLE (-3550 4350);
FORCEPROP 1 LAST BODY_TYPE PLUMBING
J 0
(-3550 4400);
DISPLAY 0.872340 (-3550 4400);
PAINT GREEN (-3550 4400);
DISPLAY INVISIBLE (-3550 4400);
FORCEPROP 1 LAST HDL_TAP TRUE
J 0
(-3225 4225);
DISPLAY 0.872340 (-3225 4225);
DISPLAY INVISIBLE (-3225 4225);
FORCEPROP 1 LAST PATH I200
J 0
(-3552 4350);
DISPLAY 0.872340 (-3552 4350);
PAINT GREEN (-3552 4350);
DISPLAY INVISIBLE (-3552 4350);
FORCEADD OFFPAGE..2
(-2550 3500);
FORCEPROP 2 LAST $XR0 39 
J 0
(-2361 3500);
DISPLAY 0.638298 (-2361 3500);
PAINT MONO (-2361 3500);
FORCEPROP 1 LAST COMMENT_BODY TRUE
J 0
(-2595 3405);
DISPLAY 0.872340 (-2595 3405);
PAINT GREEN (-2595 3405);
DISPLAY INVISIBLE (-2595 3405);
FORCEPROP 1 LAST OFFPAGE TRUE
J 0
(-2225 3375);
DISPLAY 0.723404 (-2225 3375);
PAINT GREEN (-2225 3375);
DISPLAY INVISIBLE (-2225 3375);
FORCEPROP 2 LAST CDS_LIB mstr_standard
J 0
(-2550 3500);
DISPLAY 0.723404 (-2550 3500);
PAINT MONO (-2550 3500);
DISPLAY INVISIBLE (-2550 3500);
FORCEPROP 2 LAST PATH I201
J 0
(-2350 3550);
DISPLAY 0.680851 (-2350 3550);
DISPLAY INVISIBLE (-2350 3550);
FORCEADD OFFPAGE..2
(-2550 3550);
FORCEPROP 2 LAST $XR0 39 
J 0
(-2361 3550);
DISPLAY 0.638298 (-2361 3550);
PAINT MONO (-2361 3550);
FORCEPROP 1 LAST COMMENT_BODY TRUE
J 0
(-2595 3455);
DISPLAY 0.872340 (-2595 3455);
PAINT GREEN (-2595 3455);
DISPLAY INVISIBLE (-2595 3455);
FORCEPROP 1 LAST OFFPAGE TRUE
J 0
(-2225 3425);
DISPLAY 0.723404 (-2225 3425);
PAINT GREEN (-2225 3425);
DISPLAY INVISIBLE (-2225 3425);
FORCEPROP 2 LAST CDS_LIB mstr_standard
J 0
(-2550 3550);
DISPLAY 0.723404 (-2550 3550);
PAINT MONO (-2550 3550);
DISPLAY INVISIBLE (-2550 3550);
FORCEPROP 2 LAST PATH I202
J 0
(-2350 3600);
DISPLAY 0.680851 (-2350 3600);
DISPLAY INVISIBLE (-2350 3600);
FORCEADD TAP..1
(-3350 4100);
FORCEPROP 3 LASTPIN (-3400 4100) SIG_NAME M_C_CPU1_SA_DQS_DN<5>
J 0
(-3390 4110);
DISPLAY 0.659574 (-3390 4110);
PAINT MONO (-3390 4110);
DISPLAY INVISIBLE (-3390 4110);
FORCEPROP 1 LASTPIN (-3400 4100) BN 5
J 0
(-3412 4108);
DISPLAY 0.489362 (-3412 4108);
PAINT GREEN (-3412 4108);
FORCEPROP 2 LAST CDS_LIB mstr_standard
J 0
(-3350 4100);
DISPLAY 0.723404 (-3350 4100);
PAINT MONO (-3350 4100);
DISPLAY INVISIBLE (-3350 4100);
FORCEPROP 1 LAST BODY_TYPE PLUMBING
J 0
(-3350 4150);
DISPLAY 0.872340 (-3350 4150);
PAINT GREEN (-3350 4150);
DISPLAY INVISIBLE (-3350 4150);
FORCEPROP 1 LAST HDL_TAP TRUE
J 0
(-3025 3975);
DISPLAY 0.872340 (-3025 3975);
DISPLAY INVISIBLE (-3025 3975);
FORCEPROP 1 LAST PATH I203
J 0
(-3352 4100);
DISPLAY 0.872340 (-3352 4100);
PAINT GREEN (-3352 4100);
DISPLAY INVISIBLE (-3352 4100);
FORCEADD TAP..1
(-3350 4300);
FORCEPROP 3 LASTPIN (-3400 4300) SIG_NAME M_C_CPU1_SA_DQS_DN<7>
J 0
(-3390 4310);
DISPLAY 0.659574 (-3390 4310);
PAINT MONO (-3390 4310);
DISPLAY INVISIBLE (-3390 4310);
FORCEPROP 1 LASTPIN (-3400 4300) BN 7
J 0
(-3412 4308);
DISPLAY 0.489362 (-3412 4308);
PAINT GREEN (-3412 4308);
FORCEPROP 2 LAST CDS_LIB mstr_standard
J 0
(-3350 4300);
DISPLAY 0.723404 (-3350 4300);
PAINT MONO (-3350 4300);
DISPLAY INVISIBLE (-3350 4300);
FORCEPROP 1 LAST BODY_TYPE PLUMBING
J 0
(-3350 4350);
DISPLAY 0.872340 (-3350 4350);
PAINT GREEN (-3350 4350);
DISPLAY INVISIBLE (-3350 4350);
FORCEPROP 1 LAST HDL_TAP TRUE
J 0
(-3025 4175);
DISPLAY 0.872340 (-3025 4175);
DISPLAY INVISIBLE (-3025 4175);
FORCEPROP 1 LAST PATH I204
J 0
(-3352 4300);
DISPLAY 0.872340 (-3352 4300);
PAINT GREEN (-3352 4300);
DISPLAY INVISIBLE (-3352 4300);
FORCEADD TAP..1
(-3350 4200);
FORCEPROP 3 LASTPIN (-3400 4200) SIG_NAME M_C_CPU1_SA_DQS_DN<6>
J 0
(-3390 4210);
DISPLAY 0.659574 (-3390 4210);
PAINT MONO (-3390 4210);
DISPLAY INVISIBLE (-3390 4210);
FORCEPROP 1 LASTPIN (-3400 4200) BN 6
J 0
(-3412 4208);
DISPLAY 0.489362 (-3412 4208);
PAINT GREEN (-3412 4208);
FORCEPROP 2 LAST CDS_LIB mstr_standard
J 0
(-3350 4200);
DISPLAY 0.723404 (-3350 4200);
PAINT MONO (-3350 4200);
DISPLAY INVISIBLE (-3350 4200);
FORCEPROP 1 LAST BODY_TYPE PLUMBING
J 0
(-3350 4250);
DISPLAY 0.872340 (-3350 4250);
PAINT GREEN (-3350 4250);
DISPLAY INVISIBLE (-3350 4250);
FORCEPROP 1 LAST HDL_TAP TRUE
J 0
(-3025 4075);
DISPLAY 0.872340 (-3025 4075);
DISPLAY INVISIBLE (-3025 4075);
FORCEPROP 1 LAST PATH I205
J 0
(-3352 4200);
DISPLAY 0.872340 (-3352 4200);
PAINT GREEN (-3352 4200);
DISPLAY INVISIBLE (-3352 4200);
FORCEADD TAP..1
(-3550 4250);
FORCEPROP 3 LASTPIN (-3600 4250) SIG_NAME M_C_CPU1_SA_DQS_DP<6>
J 0
(-3590 4260);
DISPLAY 0.659574 (-3590 4260);
PAINT MONO (-3590 4260);
DISPLAY INVISIBLE (-3590 4260);
FORCEPROP 1 LASTPIN (-3600 4250) BN 6
J 0
(-3612 4258);
DISPLAY 0.489362 (-3612 4258);
PAINT GREEN (-3612 4258);
FORCEPROP 2 LAST CDS_LIB mstr_standard
J 0
(-3550 4250);
DISPLAY 0.723404 (-3550 4250);
PAINT MONO (-3550 4250);
DISPLAY INVISIBLE (-3550 4250);
FORCEPROP 1 LAST BODY_TYPE PLUMBING
J 0
(-3550 4300);
DISPLAY 0.872340 (-3550 4300);
PAINT GREEN (-3550 4300);
DISPLAY INVISIBLE (-3550 4300);
FORCEPROP 1 LAST HDL_TAP TRUE
J 0
(-3225 4125);
DISPLAY 0.872340 (-3225 4125);
DISPLAY INVISIBLE (-3225 4125);
FORCEPROP 1 LAST PATH I206
J 0
(-3552 4250);
DISPLAY 0.872340 (-3552 4250);
PAINT GREEN (-3552 4250);
DISPLAY INVISIBLE (-3552 4250);
FORCEADD TAP..1
(-3550 4150);
FORCEPROP 3 LASTPIN (-3600 4150) SIG_NAME M_C_CPU1_SA_DQS_DP<5>
J 0
(-3590 4160);
DISPLAY 0.659574 (-3590 4160);
PAINT MONO (-3590 4160);
DISPLAY INVISIBLE (-3590 4160);
FORCEPROP 1 LASTPIN (-3600 4150) BN 5
J 0
(-3612 4158);
DISPLAY 0.489362 (-3612 4158);
PAINT GREEN (-3612 4158);
FORCEPROP 2 LAST CDS_LIB mstr_standard
J 0
(-3550 4150);
DISPLAY 0.723404 (-3550 4150);
PAINT MONO (-3550 4150);
DISPLAY INVISIBLE (-3550 4150);
FORCEPROP 1 LAST BODY_TYPE PLUMBING
J 0
(-3550 4200);
DISPLAY 0.872340 (-3550 4200);
PAINT GREEN (-3550 4200);
DISPLAY INVISIBLE (-3550 4200);
FORCEPROP 1 LAST HDL_TAP TRUE
J 0
(-3225 4025);
DISPLAY 0.872340 (-3225 4025);
DISPLAY INVISIBLE (-3225 4025);
FORCEPROP 1 LAST PATH I207
J 0
(-3552 4150);
DISPLAY 0.872340 (-3552 4150);
PAINT GREEN (-3552 4150);
DISPLAY INVISIBLE (-3552 4150);
FORCEADD TAP..1
(-3350 3900);
FORCEPROP 3 LASTPIN (-3400 3900) SIG_NAME M_C_CPU1_SA_DQS_DN<3>
J 0
(-3390 3910);
DISPLAY 0.659574 (-3390 3910);
PAINT MONO (-3390 3910);
DISPLAY INVISIBLE (-3390 3910);
FORCEPROP 1 LASTPIN (-3400 3900) BN 3
J 0
(-3412 3908);
DISPLAY 0.489362 (-3412 3908);
PAINT GREEN (-3412 3908);
FORCEPROP 2 LAST CDS_LIB mstr_standard
J 0
(-3350 3900);
DISPLAY 0.723404 (-3350 3900);
PAINT MONO (-3350 3900);
DISPLAY INVISIBLE (-3350 3900);
FORCEPROP 1 LAST BODY_TYPE PLUMBING
J 0
(-3350 3950);
DISPLAY 0.872340 (-3350 3950);
PAINT GREEN (-3350 3950);
DISPLAY INVISIBLE (-3350 3950);
FORCEPROP 1 LAST HDL_TAP TRUE
J 0
(-3025 3775);
DISPLAY 0.872340 (-3025 3775);
DISPLAY INVISIBLE (-3025 3775);
FORCEPROP 1 LAST PATH I208
J 0
(-3352 3900);
DISPLAY 0.872340 (-3352 3900);
PAINT GREEN (-3352 3900);
DISPLAY INVISIBLE (-3352 3900);
FORCEADD TAP..1
(-3350 4000);
FORCEPROP 3 LASTPIN (-3400 4000) SIG_NAME M_C_CPU1_SA_DQS_DN<4>
J 0
(-3390 4010);
DISPLAY 0.659574 (-3390 4010);
PAINT MONO (-3390 4010);
DISPLAY INVISIBLE (-3390 4010);
FORCEPROP 1 LASTPIN (-3400 4000) BN 4
J 0
(-3412 4008);
DISPLAY 0.489362 (-3412 4008);
PAINT GREEN (-3412 4008);
FORCEPROP 2 LAST CDS_LIB mstr_standard
J 0
(-3350 4000);
DISPLAY 0.723404 (-3350 4000);
PAINT MONO (-3350 4000);
DISPLAY INVISIBLE (-3350 4000);
FORCEPROP 1 LAST BODY_TYPE PLUMBING
J 0
(-3350 4050);
DISPLAY 0.872340 (-3350 4050);
PAINT GREEN (-3350 4050);
DISPLAY INVISIBLE (-3350 4050);
FORCEPROP 1 LAST HDL_TAP TRUE
J 0
(-3025 3875);
DISPLAY 0.872340 (-3025 3875);
DISPLAY INVISIBLE (-3025 3875);
FORCEPROP 1 LAST PATH I209
J 0
(-3352 4000);
DISPLAY 0.872340 (-3352 4000);
PAINT GREEN (-3352 4000);
DISPLAY INVISIBLE (-3352 4000);
FORCEADD OFFPAGE..1
(-8500 5450);
FORCEPROP 2 LAST $XR0 39 
J 0
(-8721 5450);
DISPLAY 0.638298 (-8721 5450);
PAINT MONO (-8721 5450);
FORCEPROP 2 LAST PATH I21
J 0
(-8700 5500);
DISPLAY 1.021277 (-8700 5500);
DISPLAY INVISIBLE (-8700 5500);
FORCEPROP 1 LAST COMMENT_BODY TRUE
J 0
(-8375 5350);
DISPLAY 0.872340 (-8375 5350);
PAINT GREEN (-8375 5350);
DISPLAY INVISIBLE (-8375 5350);
FORCEPROP 1 LAST OFFPAGE TRUE
J 0
(-8175 5325);
DISPLAY 0.872340 (-8175 5325);
PAINT GREEN (-8175 5325);
DISPLAY INVISIBLE (-8175 5325);
FORCEPROP 2 LAST CDS_LIB mstr_standard
J 0
(-8500 5450);
DISPLAY 0.723404 (-8500 5450);
PAINT MONO (-8500 5450);
DISPLAY INVISIBLE (-8500 5450);
FORCEADD TAP..1
(-3550 4050);
FORCEPROP 3 LASTPIN (-3600 4050) SIG_NAME M_C_CPU1_SA_DQS_DP<4>
J 0
(-3590 4060);
DISPLAY 0.659574 (-3590 4060);
PAINT MONO (-3590 4060);
DISPLAY INVISIBLE (-3590 4060);
FORCEPROP 1 LASTPIN (-3600 4050) BN 4
J 0
(-3612 4058);
DISPLAY 0.489362 (-3612 4058);
PAINT GREEN (-3612 4058);
FORCEPROP 2 LAST CDS_LIB mstr_standard
J 0
(-3550 4050);
DISPLAY 0.723404 (-3550 4050);
PAINT MONO (-3550 4050);
DISPLAY INVISIBLE (-3550 4050);
FORCEPROP 1 LAST BODY_TYPE PLUMBING
J 0
(-3550 4100);
DISPLAY 0.872340 (-3550 4100);
PAINT GREEN (-3550 4100);
DISPLAY INVISIBLE (-3550 4100);
FORCEPROP 1 LAST HDL_TAP TRUE
J 0
(-3225 3925);
DISPLAY 0.872340 (-3225 3925);
DISPLAY INVISIBLE (-3225 3925);
FORCEPROP 1 LAST PATH I210
J 0
(-3552 4050);
DISPLAY 0.872340 (-3552 4050);
PAINT GREEN (-3552 4050);
DISPLAY INVISIBLE (-3552 4050);
FORCEADD TAP..1
(-3550 3950);
FORCEPROP 3 LASTPIN (-3600 3950) SIG_NAME M_C_CPU1_SA_DQS_DP<3>
J 0
(-3590 3960);
DISPLAY 0.659574 (-3590 3960);
PAINT MONO (-3590 3960);
DISPLAY INVISIBLE (-3590 3960);
FORCEPROP 1 LASTPIN (-3600 3950) BN 3
J 0
(-3612 3958);
DISPLAY 0.489362 (-3612 3958);
PAINT GREEN (-3612 3958);
FORCEPROP 2 LAST CDS_LIB mstr_standard
J 0
(-3550 3950);
DISPLAY 0.723404 (-3550 3950);
PAINT MONO (-3550 3950);
DISPLAY INVISIBLE (-3550 3950);
FORCEPROP 1 LAST BODY_TYPE PLUMBING
J 0
(-3550 4000);
DISPLAY 0.872340 (-3550 4000);
PAINT GREEN (-3550 4000);
DISPLAY INVISIBLE (-3550 4000);
FORCEPROP 1 LAST HDL_TAP TRUE
J 0
(-3225 3825);
DISPLAY 0.872340 (-3225 3825);
DISPLAY INVISIBLE (-3225 3825);
FORCEPROP 1 LAST PATH I211
J 0
(-3552 3950);
DISPLAY 0.872340 (-3552 3950);
PAINT GREEN (-3552 3950);
DISPLAY INVISIBLE (-3552 3950);
FORCEADD TAP..1
(-3350 3600);
FORCEPROP 3 LASTPIN (-3400 3600) SIG_NAME M_C_CPU1_SA_DQS_DN<0>
J 0
(-3390 3610);
DISPLAY 0.659574 (-3390 3610);
PAINT MONO (-3390 3610);
DISPLAY INVISIBLE (-3390 3610);
FORCEPROP 1 LASTPIN (-3400 3600) BN 0
J 0
(-3412 3608);
DISPLAY 0.489362 (-3412 3608);
PAINT GREEN (-3412 3608);
FORCEPROP 2 LAST CDS_LIB mstr_standard
J 0
(-3350 3600);
DISPLAY 0.723404 (-3350 3600);
PAINT MONO (-3350 3600);
DISPLAY INVISIBLE (-3350 3600);
FORCEPROP 1 LAST BODY_TYPE PLUMBING
J 0
(-3350 3650);
DISPLAY 0.872340 (-3350 3650);
PAINT GREEN (-3350 3650);
DISPLAY INVISIBLE (-3350 3650);
FORCEPROP 1 LAST HDL_TAP TRUE
J 0
(-3025 3475);
DISPLAY 0.872340 (-3025 3475);
DISPLAY INVISIBLE (-3025 3475);
FORCEPROP 1 LAST PATH I212
J 0
(-3352 3600);
DISPLAY 0.872340 (-3352 3600);
PAINT GREEN (-3352 3600);
DISPLAY INVISIBLE (-3352 3600);
FORCEADD TAP..1
(-3350 3800);
FORCEPROP 3 LASTPIN (-3400 3800) SIG_NAME M_C_CPU1_SA_DQS_DN<2>
J 0
(-3390 3810);
DISPLAY 0.659574 (-3390 3810);
PAINT MONO (-3390 3810);
DISPLAY INVISIBLE (-3390 3810);
FORCEPROP 1 LASTPIN (-3400 3800) BN 2
J 0
(-3412 3808);
DISPLAY 0.489362 (-3412 3808);
PAINT GREEN (-3412 3808);
FORCEPROP 2 LAST CDS_LIB mstr_standard
J 0
(-3350 3800);
DISPLAY 0.723404 (-3350 3800);
PAINT MONO (-3350 3800);
DISPLAY INVISIBLE (-3350 3800);
FORCEPROP 1 LAST BODY_TYPE PLUMBING
J 0
(-3350 3850);
DISPLAY 0.872340 (-3350 3850);
PAINT GREEN (-3350 3850);
DISPLAY INVISIBLE (-3350 3850);
FORCEPROP 1 LAST HDL_TAP TRUE
J 0
(-3025 3675);
DISPLAY 0.872340 (-3025 3675);
DISPLAY INVISIBLE (-3025 3675);
FORCEPROP 1 LAST PATH I213
J 0
(-3352 3800);
DISPLAY 0.872340 (-3352 3800);
PAINT GREEN (-3352 3800);
DISPLAY INVISIBLE (-3352 3800);
FORCEADD TAP..1
(-3350 3700);
FORCEPROP 3 LASTPIN (-3400 3700) SIG_NAME M_C_CPU1_SA_DQS_DN<1>
J 0
(-3390 3710);
DISPLAY 0.659574 (-3390 3710);
PAINT MONO (-3390 3710);
DISPLAY INVISIBLE (-3390 3710);
FORCEPROP 1 LASTPIN (-3400 3700) BN 1
J 0
(-3412 3708);
DISPLAY 0.489362 (-3412 3708);
PAINT GREEN (-3412 3708);
FORCEPROP 2 LAST CDS_LIB mstr_standard
J 0
(-3350 3700);
DISPLAY 0.723404 (-3350 3700);
PAINT MONO (-3350 3700);
DISPLAY INVISIBLE (-3350 3700);
FORCEPROP 1 LAST BODY_TYPE PLUMBING
J 0
(-3350 3750);
DISPLAY 0.872340 (-3350 3750);
PAINT GREEN (-3350 3750);
DISPLAY INVISIBLE (-3350 3750);
FORCEPROP 1 LAST HDL_TAP TRUE
J 0
(-3025 3575);
DISPLAY 0.872340 (-3025 3575);
DISPLAY INVISIBLE (-3025 3575);
FORCEPROP 1 LAST PATH I214
J 0
(-3352 3700);
DISPLAY 0.872340 (-3352 3700);
PAINT GREEN (-3352 3700);
DISPLAY INVISIBLE (-3352 3700);
FORCEADD TAP..1
(-3550 3650);
FORCEPROP 3 LASTPIN (-3600 3650) SIG_NAME M_C_CPU1_SA_DQS_DP<0>
J 0
(-3590 3660);
DISPLAY 0.659574 (-3590 3660);
PAINT MONO (-3590 3660);
DISPLAY INVISIBLE (-3590 3660);
FORCEPROP 1 LASTPIN (-3600 3650) BN 0
J 0
(-3612 3658);
DISPLAY 0.489362 (-3612 3658);
PAINT GREEN (-3612 3658);
FORCEPROP 2 LAST CDS_LIB mstr_standard
J 0
(-3550 3650);
DISPLAY 0.723404 (-3550 3650);
PAINT MONO (-3550 3650);
DISPLAY INVISIBLE (-3550 3650);
FORCEPROP 1 LAST BODY_TYPE PLUMBING
J 0
(-3550 3700);
DISPLAY 0.872340 (-3550 3700);
PAINT GREEN (-3550 3700);
DISPLAY INVISIBLE (-3550 3700);
FORCEPROP 1 LAST HDL_TAP TRUE
J 0
(-3225 3525);
DISPLAY 0.872340 (-3225 3525);
DISPLAY INVISIBLE (-3225 3525);
FORCEPROP 1 LAST PATH I215
J 0
(-3552 3650);
DISPLAY 0.872340 (-3552 3650);
PAINT GREEN (-3552 3650);
DISPLAY INVISIBLE (-3552 3650);
FORCEADD TAP..1
(-3350 3350);
FORCEPROP 3 LASTPIN (-3400 3350) SIG_NAME M_C_CPU1_SB_DQS_DN<8>
J 0
(-3390 3360);
DISPLAY 0.659574 (-3390 3360);
PAINT MONO (-3390 3360);
DISPLAY INVISIBLE (-3390 3360);
FORCEPROP 1 LASTPIN (-3400 3350) BN 8
J 0
(-3412 3358);
DISPLAY 0.489362 (-3412 3358);
PAINT GREEN (-3412 3358);
FORCEPROP 2 LAST CDS_LIB mstr_standard
J 0
(-3350 3350);
DISPLAY 0.723404 (-3350 3350);
PAINT MONO (-3350 3350);
DISPLAY INVISIBLE (-3350 3350);
FORCEPROP 1 LAST BODY_TYPE PLUMBING
J 0
(-3350 3400);
DISPLAY 0.872340 (-3350 3400);
PAINT GREEN (-3350 3400);
DISPLAY INVISIBLE (-3350 3400);
FORCEPROP 1 LAST HDL_TAP TRUE
J 0
(-3025 3225);
DISPLAY 0.872340 (-3025 3225);
DISPLAY INVISIBLE (-3025 3225);
FORCEPROP 1 LAST PATH I216
J 0
(-3352 3350);
DISPLAY 0.872340 (-3352 3350);
PAINT GREEN (-3352 3350);
DISPLAY INVISIBLE (-3352 3350);
FORCEADD TAP..1
(-3350 3450);
FORCEPROP 3 LASTPIN (-3400 3450) SIG_NAME M_C_CPU1_SB_DQS_DN<9>
J 0
(-3390 3460);
DISPLAY 0.659574 (-3390 3460);
PAINT MONO (-3390 3460);
DISPLAY INVISIBLE (-3390 3460);
FORCEPROP 1 LASTPIN (-3400 3450) BN 9
J 0
(-3412 3458);
DISPLAY 0.489362 (-3412 3458);
PAINT GREEN (-3412 3458);
FORCEPROP 2 LAST CDS_LIB mstr_standard
J 0
(-3350 3450);
DISPLAY 0.723404 (-3350 3450);
PAINT MONO (-3350 3450);
DISPLAY INVISIBLE (-3350 3450);
FORCEPROP 1 LAST BODY_TYPE PLUMBING
J 0
(-3350 3500);
DISPLAY 0.872340 (-3350 3500);
PAINT GREEN (-3350 3500);
DISPLAY INVISIBLE (-3350 3500);
FORCEPROP 1 LAST HDL_TAP TRUE
J 0
(-3025 3325);
DISPLAY 0.872340 (-3025 3325);
DISPLAY INVISIBLE (-3025 3325);
FORCEPROP 1 LAST PATH I217
J 0
(-3352 3450);
DISPLAY 0.872340 (-3352 3450);
PAINT GREEN (-3352 3450);
DISPLAY INVISIBLE (-3352 3450);
FORCEADD TAP..1
(-3550 3500);
FORCEPROP 3 LASTPIN (-3600 3500) SIG_NAME M_C_CPU1_SB_DQS_DP<9>
J 0
(-3590 3510);
DISPLAY 0.659574 (-3590 3510);
PAINT MONO (-3590 3510);
DISPLAY INVISIBLE (-3590 3510);
FORCEPROP 1 LASTPIN (-3600 3500) BN 9
J 0
(-3612 3508);
DISPLAY 0.489362 (-3612 3508);
PAINT GREEN (-3612 3508);
FORCEPROP 2 LAST CDS_LIB mstr_standard
J 0
(-3550 3500);
DISPLAY 0.723404 (-3550 3500);
PAINT MONO (-3550 3500);
DISPLAY INVISIBLE (-3550 3500);
FORCEPROP 1 LAST BODY_TYPE PLUMBING
J 0
(-3550 3550);
DISPLAY 0.872340 (-3550 3550);
PAINT GREEN (-3550 3550);
DISPLAY INVISIBLE (-3550 3550);
FORCEPROP 1 LAST HDL_TAP TRUE
J 0
(-3225 3375);
DISPLAY 0.872340 (-3225 3375);
DISPLAY INVISIBLE (-3225 3375);
FORCEPROP 1 LAST PATH I218
J 0
(-3552 3500);
DISPLAY 0.872340 (-3552 3500);
PAINT GREEN (-3552 3500);
DISPLAY INVISIBLE (-3552 3500);
FORCEADD TAP..1
(-3550 3400);
FORCEPROP 3 LASTPIN (-3600 3400) SIG_NAME M_C_CPU1_SB_DQS_DP<8>
J 0
(-3590 3410);
DISPLAY 0.659574 (-3590 3410);
PAINT MONO (-3590 3410);
DISPLAY INVISIBLE (-3590 3410);
FORCEPROP 1 LASTPIN (-3600 3400) BN 8
J 0
(-3612 3408);
DISPLAY 0.489362 (-3612 3408);
PAINT GREEN (-3612 3408);
FORCEPROP 2 LAST CDS_LIB mstr_standard
J 0
(-3550 3400);
DISPLAY 0.723404 (-3550 3400);
PAINT MONO (-3550 3400);
DISPLAY INVISIBLE (-3550 3400);
FORCEPROP 1 LAST BODY_TYPE PLUMBING
J 0
(-3550 3450);
DISPLAY 0.872340 (-3550 3450);
PAINT GREEN (-3550 3450);
DISPLAY INVISIBLE (-3550 3450);
FORCEPROP 1 LAST HDL_TAP TRUE
J 0
(-3225 3275);
DISPLAY 0.872340 (-3225 3275);
DISPLAY INVISIBLE (-3225 3275);
FORCEPROP 1 LAST PATH I219
J 0
(-3552 3400);
DISPLAY 0.872340 (-3552 3400);
PAINT GREEN (-3552 3400);
DISPLAY INVISIBLE (-3552 3400);
FORCEADD SCONN288_DDR506112002KQ..1
(-7050 3650);
FORCEPROP 1 LAST LOCATION J28
J 0
(-7500 5725);
DISPLAY 0.468085 (-7500 5725);
PAINT SKYBLUE (-7500 5725);
FORCEPROP 0 LAST $SEC 1
J 0
(-7500 5875);
DISPLAY 0.680851 (-7500 5875);
PAINT MONO (-7500 5875);
DISPLAY INVISIBLE (-7500 5875);
FORCEPROP 2 LAST CDS_SEC 1
J 0
(-7500 5875);
DISPLAY 1.021277 (-7500 5875);
DISPLAY INVISIBLE (-7500 5875);
FORCEPROP 0 LASTPIN (-7650 3050) $PN 62
J 2
(-7660 3060);
DISPLAY 0.680851 (-7660 3060);
PAINT MONO (-7660 3060);
FORCEPROP 0 LASTPIN (-7650 5100) $PN 66
J 2
(-7660 5110);
DISPLAY 0.680851 (-7660 5110);
PAINT MONO (-7660 5110);
FORCEPROP 0 LASTPIN (-7650 4700) $PN 76
J 2
(-7660 4710);
DISPLAY 0.680851 (-7660 4710);
PAINT MONO (-7660 4710);
FORCEPROP 0 LASTPIN (-7650 5150) $PN 211
J 2
(-7660 5160);
DISPLAY 0.680851 (-7660 5160);
PAINT MONO (-7660 5160);
FORCEPROP 0 LASTPIN (-7650 4750) $PN 221
J 2
(-7660 4760);
DISPLAY 0.680851 (-7660 4760);
PAINT MONO (-7660 4760);
FORCEPROP 0 LASTPIN (-7650 5200) $PN 68
J 2
(-7660 5210);
DISPLAY 0.680851 (-7660 5210);
PAINT MONO (-7660 5210);
FORCEPROP 0 LASTPIN (-7650 4800) $PN 78
J 2
(-7660 4810);
DISPLAY 0.680851 (-7660 4810);
PAINT MONO (-7660 4810);
FORCEPROP 0 LASTPIN (-7650 5250) $PN 213
J 2
(-7660 5260);
DISPLAY 0.680851 (-7660 5260);
PAINT MONO (-7660 5260);
FORCEPROP 0 LASTPIN (-7650 4850) $PN 223
J 2
(-7660 4860);
DISPLAY 0.680851 (-7660 4860);
PAINT MONO (-7660 4860);
FORCEPROP 0 LASTPIN (-7650 5300) $PN 70
J 2
(-7660 5310);
DISPLAY 0.680851 (-7660 5310);
PAINT MONO (-7660 5310);
FORCEPROP 0 LASTPIN (-7650 4900) $PN 80
J 2
(-7660 4910);
DISPLAY 0.680851 (-7660 4910);
PAINT MONO (-7660 4910);
FORCEPROP 0 LASTPIN (-7650 5350) $PN 215
J 2
(-7660 5360);
DISPLAY 0.680851 (-7660 5360);
PAINT MONO (-7660 5360);
FORCEPROP 0 LASTPIN (-7650 4950) $PN 225
J 2
(-7660 4960);
DISPLAY 0.680851 (-7660 4960);
PAINT MONO (-7660 4960);
FORCEPROP 0 LASTPIN (-7650 5400) $PN 72
J 2
(-7660 5410);
DISPLAY 0.680851 (-7660 5410);
PAINT MONO (-7660 5410);
FORCEPROP 0 LASTPIN (-7650 5000) $PN 82
J 2
(-7660 5010);
DISPLAY 0.680851 (-7660 5010);
PAINT MONO (-7660 5010);
FORCEPROP 0 LASTPIN (-7650 3650) $PN 51
J 2
(-7660 3660);
DISPLAY 0.680851 (-7660 3660);
PAINT MONO (-7660 3660);
FORCEPROP 0 LASTPIN (-7650 3200) $PN 96
J 2
(-7660 3210);
DISPLAY 0.680851 (-7660 3210);
PAINT MONO (-7660 3210);
FORCEPROP 0 LASTPIN (-7650 3700) $PN 53
J 2
(-7660 3710);
DISPLAY 0.680851 (-7660 3710);
PAINT MONO (-7660 3710);
FORCEPROP 0 LASTPIN (-7650 3250) $PN 98
J 2
(-7660 3260);
DISPLAY 0.680851 (-7660 3260);
PAINT MONO (-7660 3260);
FORCEPROP 0 LASTPIN (-7650 3750) $PN 196
J 2
(-7660 3760);
DISPLAY 0.680851 (-7660 3760);
PAINT MONO (-7660 3760);
FORCEPROP 0 LASTPIN (-7650 3300) $PN 241
J 2
(-7660 3310);
DISPLAY 0.680851 (-7660 3310);
PAINT MONO (-7660 3310);
FORCEPROP 0 LASTPIN (-7650 3800) $PN 198
J 2
(-7660 3810);
DISPLAY 0.680851 (-7660 3810);
PAINT MONO (-7660 3810);
FORCEPROP 0 LASTPIN (-7650 3350) $PN 243
J 2
(-7660 3360);
DISPLAY 0.680851 (-7660 3360);
PAINT MONO (-7660 3360);
FORCEPROP 0 LASTPIN (-7650 3850) $PN 58
J 2
(-7660 3860);
DISPLAY 0.680851 (-7660 3860);
PAINT MONO (-7660 3860);
FORCEPROP 0 LASTPIN (-7650 3400) $PN 89
J 2
(-7660 3410);
DISPLAY 0.680851 (-7660 3410);
PAINT MONO (-7660 3410);
FORCEPROP 0 LASTPIN (-7650 3900) $PN 60
J 2
(-7660 3910);
DISPLAY 0.680851 (-7660 3910);
PAINT MONO (-7660 3910);
FORCEPROP 0 LASTPIN (-7650 3450) $PN 91
J 2
(-7660 3460);
DISPLAY 0.680851 (-7660 3460);
PAINT MONO (-7660 3460);
FORCEPROP 0 LASTPIN (-7650 3950) $PN 203
J 2
(-7660 3960);
DISPLAY 0.680851 (-7660 3960);
PAINT MONO (-7660 3960);
FORCEPROP 0 LASTPIN (-7650 3500) $PN 234
J 2
(-7660 3510);
DISPLAY 0.680851 (-7660 3510);
PAINT MONO (-7660 3510);
FORCEPROP 0 LASTPIN (-7650 4000) $PN 205
J 2
(-7660 4010);
DISPLAY 0.680851 (-7660 4010);
PAINT MONO (-7660 4010);
FORCEPROP 0 LASTPIN (-7650 3550) $PN 236
J 2
(-7660 3560);
DISPLAY 0.680851 (-7660 3560);
PAINT MONO (-7660 3560);
FORCEPROP 0 LASTPIN (-7650 4100) $PN 218
J 2
(-7660 4110);
DISPLAY 0.680851 (-7660 4110);
PAINT MONO (-7660 4110);
FORCEPROP 0 LASTPIN (-7650 4150) $PN 217
J 2
(-7660 4160);
DISPLAY 0.680851 (-7660 4160);
PAINT MONO (-7660 4160);
FORCEPROP 0 LASTPIN (-7650 4400) $PN 64
J 2
(-7660 4410);
DISPLAY 0.680851 (-7660 4410);
PAINT MONO (-7660 4410);
FORCEPROP 0 LASTPIN (-7650 4250) $PN 84
J 2
(-7660 4260);
DISPLAY 0.680851 (-7660 4260);
PAINT MONO (-7660 4260);
FORCEPROP 0 LASTPIN (-7650 4450) $PN 209
J 2
(-7660 4460);
DISPLAY 0.680851 (-7660 4460);
PAINT MONO (-7660 4460);
FORCEPROP 0 LASTPIN (-7650 4300) $PN 229
J 2
(-7660 4310);
DISPLAY 0.680851 (-7660 4310);
PAINT MONO (-7660 4310);
FORCEPROP 0 LASTPIN (-6450 3850) $PN 7
J 0
(-6440 3860);
DISPLAY 0.680851 (-6440 3860);
PAINT MONO (-6440 3860);
FORCEPROP 0 LASTPIN (-6450 2200) $PN 100
J 0
(-6440 2210);
DISPLAY 0.680851 (-6440 2210);
PAINT MONO (-6440 2210);
FORCEPROP 0 LASTPIN (-6450 3900) $PN 9
J 0
(-6440 3910);
DISPLAY 0.680851 (-6440 3910);
PAINT MONO (-6440 3910);
FORCEPROP 0 LASTPIN (-6450 2250) $PN 102
J 0
(-6440 2260);
DISPLAY 0.680851 (-6440 2260);
PAINT MONO (-6440 2260);
FORCEPROP 0 LASTPIN (-6450 3950) $PN 152
J 0
(-6440 3960);
DISPLAY 0.680851 (-6440 3960);
PAINT MONO (-6440 3960);
FORCEPROP 0 LASTPIN (-6450 2300) $PN 245
J 0
(-6440 2310);
DISPLAY 0.680851 (-6440 2310);
PAINT MONO (-6440 2310);
FORCEPROP 0 LASTPIN (-6450 4000) $PN 154
J 0
(-6440 4010);
DISPLAY 0.680851 (-6440 4010);
PAINT MONO (-6440 4010);
FORCEPROP 0 LASTPIN (-6450 2350) $PN 247
J 0
(-6440 2360);
DISPLAY 0.680851 (-6440 2360);
PAINT MONO (-6440 2360);
FORCEPROP 0 LASTPIN (-6450 4050) $PN 14
J 0
(-6440 4060);
DISPLAY 0.680851 (-6440 4060);
PAINT MONO (-6440 4060);
FORCEPROP 0 LASTPIN (-6450 2400) $PN 107
J 0
(-6440 2410);
DISPLAY 0.680851 (-6440 2410);
PAINT MONO (-6440 2410);
FORCEPROP 0 LASTPIN (-6450 4100) $PN 16
J 0
(-6440 4110);
DISPLAY 0.680851 (-6440 4110);
PAINT MONO (-6440 4110);
FORCEPROP 0 LASTPIN (-6450 2450) $PN 109
J 0
(-6440 2460);
DISPLAY 0.680851 (-6440 2460);
PAINT MONO (-6440 2460);
FORCEPROP 0 LASTPIN (-6450 4150) $PN 159
J 0
(-6440 4160);
DISPLAY 0.680851 (-6440 4160);
PAINT MONO (-6440 4160);
FORCEPROP 0 LASTPIN (-6450 2500) $PN 252
J 0
(-6440 2510);
DISPLAY 0.680851 (-6440 2510);
PAINT MONO (-6440 2510);
FORCEPROP 0 LASTPIN (-6450 4200) $PN 161
J 0
(-6440 4210);
DISPLAY 0.680851 (-6440 4210);
PAINT MONO (-6440 4210);
FORCEPROP 0 LASTPIN (-6450 2550) $PN 254
J 0
(-6440 2560);
DISPLAY 0.680851 (-6440 2560);
PAINT MONO (-6440 2560);
FORCEPROP 0 LASTPIN (-6450 4250) $PN 18
J 0
(-6440 4260);
DISPLAY 0.680851 (-6440 4260);
PAINT MONO (-6440 4260);
FORCEPROP 0 LASTPIN (-6450 2600) $PN 111
J 0
(-6440 2610);
DISPLAY 0.680851 (-6440 2610);
PAINT MONO (-6440 2610);
FORCEPROP 0 LASTPIN (-6450 4300) $PN 20
J 0
(-6440 4310);
DISPLAY 0.680851 (-6440 4310);
PAINT MONO (-6440 4310);
FORCEPROP 0 LASTPIN (-6450 2650) $PN 113
J 0
(-6440 2660);
DISPLAY 0.680851 (-6440 2660);
PAINT MONO (-6440 2660);
FORCEPROP 0 LASTPIN (-6450 4350) $PN 163
J 0
(-6440 4360);
DISPLAY 0.680851 (-6440 4360);
PAINT MONO (-6440 4360);
FORCEPROP 0 LASTPIN (-6450 2700) $PN 256
J 0
(-6440 2710);
DISPLAY 0.680851 (-6440 2710);
PAINT MONO (-6440 2710);
FORCEPROP 0 LASTPIN (-6450 4400) $PN 165
J 0
(-6440 4410);
DISPLAY 0.680851 (-6440 4410);
PAINT MONO (-6440 4410);
FORCEPROP 0 LASTPIN (-6450 2750) $PN 258
J 0
(-6440 2760);
DISPLAY 0.680851 (-6440 2760);
PAINT MONO (-6440 2760);
FORCEPROP 0 LASTPIN (-6450 4450) $PN 25
J 0
(-6440 4460);
DISPLAY 0.680851 (-6440 4460);
PAINT MONO (-6440 4460);
FORCEPROP 0 LASTPIN (-6450 2800) $PN 118
J 0
(-6440 2810);
DISPLAY 0.680851 (-6440 2810);
PAINT MONO (-6440 2810);
FORCEPROP 0 LASTPIN (-6450 4500) $PN 27
J 0
(-6440 4510);
DISPLAY 0.680851 (-6440 4510);
PAINT MONO (-6440 4510);
FORCEPROP 0 LASTPIN (-6450 2850) $PN 120
J 0
(-6440 2860);
DISPLAY 0.680851 (-6440 2860);
PAINT MONO (-6440 2860);
FORCEPROP 0 LASTPIN (-6450 4550) $PN 170
J 0
(-6440 4560);
DISPLAY 0.680851 (-6440 4560);
PAINT MONO (-6440 4560);
FORCEPROP 0 LASTPIN (-6450 2900) $PN 263
J 0
(-6440 2910);
DISPLAY 0.680851 (-6440 2910);
PAINT MONO (-6440 2910);
FORCEPROP 0 LASTPIN (-6450 4600) $PN 172
J 0
(-6440 4610);
DISPLAY 0.680851 (-6440 4610);
PAINT MONO (-6440 4610);
FORCEPROP 0 LASTPIN (-6450 2950) $PN 265
J 0
(-6440 2960);
DISPLAY 0.680851 (-6440 2960);
PAINT MONO (-6440 2960);
FORCEPROP 0 LASTPIN (-6450 4650) $PN 29
J 0
(-6440 4660);
DISPLAY 0.680851 (-6440 4660);
PAINT MONO (-6440 4660);
FORCEPROP 0 LASTPIN (-6450 3000) $PN 122
J 0
(-6440 3010);
DISPLAY 0.680851 (-6440 3010);
PAINT MONO (-6440 3010);
FORCEPROP 0 LASTPIN (-6450 4700) $PN 31
J 0
(-6440 4710);
DISPLAY 0.680851 (-6440 4710);
PAINT MONO (-6440 4710);
FORCEPROP 0 LASTPIN (-6450 3050) $PN 124
J 0
(-6440 3060);
DISPLAY 0.680851 (-6440 3060);
PAINT MONO (-6440 3060);
FORCEPROP 0 LASTPIN (-6450 4750) $PN 174
J 0
(-6440 4760);
DISPLAY 0.680851 (-6440 4760);
PAINT MONO (-6440 4760);
FORCEPROP 0 LASTPIN (-6450 3100) $PN 267
J 0
(-6440 3110);
DISPLAY 0.680851 (-6440 3110);
PAINT MONO (-6440 3110);
FORCEPROP 0 LASTPIN (-6450 4800) $PN 176
J 0
(-6440 4810);
DISPLAY 0.680851 (-6440 4810);
PAINT MONO (-6440 4810);
FORCEPROP 0 LASTPIN (-6450 3150) $PN 269
J 0
(-6440 3160);
DISPLAY 0.680851 (-6440 3160);
PAINT MONO (-6440 3160);
FORCEPROP 0 LASTPIN (-6450 4850) $PN 36
J 0
(-6440 4860);
DISPLAY 0.680851 (-6440 4860);
PAINT MONO (-6440 4860);
FORCEPROP 0 LASTPIN (-6450 3200) $PN 129
J 0
(-6440 3210);
DISPLAY 0.680851 (-6440 3210);
PAINT MONO (-6440 3210);
FORCEPROP 0 LASTPIN (-6450 4900) $PN 38
J 0
(-6440 4910);
DISPLAY 0.680851 (-6440 4910);
PAINT MONO (-6440 4910);
FORCEPROP 0 LASTPIN (-6450 3250) $PN 131
J 0
(-6440 3260);
DISPLAY 0.680851 (-6440 3260);
PAINT MONO (-6440 3260);
FORCEPROP 0 LASTPIN (-6450 4950) $PN 181
J 0
(-6440 4960);
DISPLAY 0.680851 (-6440 4960);
PAINT MONO (-6440 4960);
FORCEPROP 0 LASTPIN (-6450 3300) $PN 274
J 0
(-6440 3310);
DISPLAY 0.680851 (-6440 3310);
PAINT MONO (-6440 3310);
FORCEPROP 0 LASTPIN (-6450 5000) $PN 183
J 0
(-6440 5010);
DISPLAY 0.680851 (-6440 5010);
PAINT MONO (-6440 5010);
FORCEPROP 0 LASTPIN (-6450 3350) $PN 276
J 0
(-6440 3360);
DISPLAY 0.680851 (-6440 3360);
PAINT MONO (-6440 3360);
FORCEPROP 0 LASTPIN (-6450 5050) $PN 40
J 0
(-6440 5060);
DISPLAY 0.680851 (-6440 5060);
PAINT MONO (-6440 5060);
FORCEPROP 0 LASTPIN (-6450 3400) $PN 133
J 0
(-6440 3410);
DISPLAY 0.680851 (-6440 3410);
PAINT MONO (-6440 3410);
FORCEPROP 0 LASTPIN (-6450 5100) $PN 42
J 0
(-6440 5110);
DISPLAY 0.680851 (-6440 5110);
PAINT MONO (-6440 5110);
FORCEPROP 0 LASTPIN (-6450 3450) $PN 135
J 0
(-6440 3460);
DISPLAY 0.680851 (-6440 3460);
PAINT MONO (-6440 3460);
FORCEPROP 0 LASTPIN (-6450 5150) $PN 185
J 0
(-6440 5160);
DISPLAY 0.680851 (-6440 5160);
PAINT MONO (-6440 5160);
FORCEPROP 0 LASTPIN (-6450 3500) $PN 278
J 0
(-6440 3510);
DISPLAY 0.680851 (-6440 3510);
PAINT MONO (-6440 3510);
FORCEPROP 0 LASTPIN (-6450 5200) $PN 187
J 0
(-6440 5210);
DISPLAY 0.680851 (-6440 5210);
PAINT MONO (-6440 5210);
FORCEPROP 0 LASTPIN (-6450 3550) $PN 280
J 0
(-6440 3560);
DISPLAY 0.680851 (-6440 3560);
PAINT MONO (-6440 3560);
FORCEPROP 0 LASTPIN (-6450 5250) $PN 47
J 0
(-6440 5260);
DISPLAY 0.680851 (-6440 5260);
PAINT MONO (-6440 5260);
FORCEPROP 0 LASTPIN (-6450 3600) $PN 140
J 0
(-6440 3610);
DISPLAY 0.680851 (-6440 3610);
PAINT MONO (-6440 3610);
FORCEPROP 0 LASTPIN (-6450 5300) $PN 49
J 0
(-6440 5310);
DISPLAY 0.680851 (-6440 5310);
PAINT MONO (-6440 5310);
FORCEPROP 0 LASTPIN (-6450 3650) $PN 142
J 0
(-6440 3660);
DISPLAY 0.680851 (-6440 3660);
PAINT MONO (-6440 3660);
FORCEPROP 0 LASTPIN (-6450 5350) $PN 192
J 0
(-6440 5360);
DISPLAY 0.680851 (-6440 5360);
PAINT MONO (-6440 5360);
FORCEPROP 0 LASTPIN (-6450 3700) $PN 285
J 0
(-6440 3710);
DISPLAY 0.680851 (-6440 3710);
PAINT MONO (-6440 3710);
FORCEPROP 0 LASTPIN (-6450 5400) $PN 194
J 0
(-6440 5410);
DISPLAY 0.680851 (-6440 5410);
PAINT MONO (-6440 5410);
FORCEPROP 0 LASTPIN (-6450 3750) $PN 287
J 0
(-6440 3760);
DISPLAY 0.680851 (-6440 3760);
PAINT MONO (-6440 3760);
FORCEPROP 0 LASTPIN (-7650 2900) $PN 148
J 2
(-7660 2910);
DISPLAY 0.680851 (-7660 2910);
PAINT MONO (-7660 2910);
FORCEPROP 0 LASTPIN (-7650 2800) $PN 4
J 2
(-7660 2810);
DISPLAY 0.680851 (-7660 2810);
PAINT MONO (-7660 2810);
FORCEPROP 0 LASTPIN (-7650 2850) $PN 5
J 2
(-7660 2860);
DISPLAY 0.680851 (-7660 2860);
PAINT MONO (-7660 2860);
FORCEPROP 0 LASTPIN (-7650 2000) $PN 86
J 2
(-7660 2010);
DISPLAY 0.680851 (-7660 2010);
PAINT MONO (-7660 2010);
FORCEPROP 0 LASTPIN (-7650 1950) $PN 87
J 2
(-7660 1960);
DISPLAY 0.680851 (-7660 1960);
PAINT MONO (-7660 1960);
FORCEPROP 0 LASTPIN (-7650 4600) $PN 74
J 2
(-7660 4610);
DISPLAY 0.680851 (-7660 4610);
PAINT MONO (-7660 4610);
FORCEPROP 0 LASTPIN (-7650 4550) $PN 227
J 2
(-7660 4560);
DISPLAY 0.680851 (-7660 4560);
PAINT MONO (-7660 4560);
FORCEPROP 0 LASTPIN (-7650 2550) $PN 147
J 2
(-7660 2560);
DISPLAY 0.680851 (-7660 2560);
PAINT MONO (-7660 2560);
FORCEPROP 0 LASTPIN (-7650 3100) $PN 207
J 2
(-7660 3110);
DISPLAY 0.680851 (-7660 3110);
PAINT MONO (-7660 3110);
FORCEPROP 0 LASTPIN (-7650 2150) $PN 2
J 2
(-7660 2160);
DISPLAY 0.680851 (-7660 2160);
PAINT MONO (-7660 2160);
FORCEPROP 0 LASTPIN (-7650 2200) $PN 144
J 2
(-7660 2210);
DISPLAY 0.680851 (-7660 2210);
PAINT MONO (-7660 2210);
FORCEPROP 0 LASTPIN (-7650 2250) $PN 149
J 2
(-7660 2260);
DISPLAY 0.680851 (-7660 2260);
PAINT MONO (-7660 2260);
FORCEPROP 0 LASTPIN (-7650 2300) $PN 150
J 2
(-7660 2310);
DISPLAY 0.680851 (-7660 2310);
PAINT MONO (-7660 2310);
FORCEPROP 0 LASTPIN (-7650 2350) $PN 220
J 2
(-7660 2360);
DISPLAY 0.680851 (-7660 2360);
PAINT MONO (-7660 2360);
FORCEPROP 0 LASTPIN (-7650 2400) $PN 231
J 2
(-7660 2410);
DISPLAY 0.680851 (-7660 2410);
PAINT MONO (-7660 2410);
FORCEPROP 0 LASTPIN (-7650 2450) $PN 232
J 2
(-7660 2460);
DISPLAY 0.680851 (-7660 2460);
PAINT MONO (-7660 2460);
FORCEPROP 0 LASTPIN (-7650 2950) $PN 3
J 2
(-7660 2960);
DISPLAY 0.680851 (-7660 2960);
PAINT MONO (-7660 2960);
FORCEPROP 2 LAST PART_TYPE SMLF
J 0
(-7500 5825);
DISPLAY 1.021277 (-7500 5825);
FORCEPROP 1 LAST PART_NUMBER DFHST8FS479
J 0
(-7500 5650);
DISPLAY 0.468085 (-7500 5650);
PAINT SKYBLUE (-7500 5650);
FORCEPROP 2 LAST VALUE SCONN288_DDR506112002KQ
J 0
(-7500 5775);
DISPLAY 0.489362 (-7500 5775);
PAINT SKYBLUE (-7500 5775);
FORCEPROP 1 LAST MATERIAL IO
J 0
(-7500 5575);
DISPLAY 0.468085 (-7500 5575);
PAINT SKYBLUE (-7500 5575);
FORCEPROP 1 LAST CDS_LMAN_SYM_OUTLINE -450,1900,450,-1850
J 0
(-7050 3650);
DISPLAY 0.468085 (-7050 3650);
PAINT GREEN (-7050 3650);
DISPLAY INVISIBLE (-7050 3650);
FORCEPROP 1 LAST PATH I22
J 0
(-7050 3650);
DISPLAY 0.723404 (-7050 3650);
PAINT GREEN (-7050 3650);
DISPLAY INVISIBLE (-7050 3650);
FORCEPROP 1 LAST NEEDS_NO_SIZE TRUE
J 0
(-7050 3650);
DISPLAY 0.723404 (-7050 3650);
PAINT GREEN (-7050 3650);
DISPLAY INVISIBLE (-7050 3650);
FORCEPROP 2 LAST CDS_LIB pure_quanta
J 0
(-7050 3650);
DISPLAY INVISIBLE (-7050 3650);
FORCEADD TAP..1
(-3550 3300);
FORCEPROP 3 LASTPIN (-3600 3300) SIG_NAME M_C_CPU1_SB_DQS_DP<7>
J 0
(-3590 3310);
DISPLAY 0.659574 (-3590 3310);
PAINT MONO (-3590 3310);
DISPLAY INVISIBLE (-3590 3310);
FORCEPROP 1 LASTPIN (-3600 3300) BN 7
J 0
(-3612 3308);
DISPLAY 0.489362 (-3612 3308);
PAINT GREEN (-3612 3308);
FORCEPROP 2 LAST CDS_LIB mstr_standard
J 0
(-3550 3300);
DISPLAY 0.723404 (-3550 3300);
PAINT MONO (-3550 3300);
DISPLAY INVISIBLE (-3550 3300);
FORCEPROP 1 LAST BODY_TYPE PLUMBING
J 0
(-3550 3350);
DISPLAY 0.872340 (-3550 3350);
PAINT GREEN (-3550 3350);
DISPLAY INVISIBLE (-3550 3350);
FORCEPROP 1 LAST HDL_TAP TRUE
J 0
(-3225 3175);
DISPLAY 0.872340 (-3225 3175);
DISPLAY INVISIBLE (-3225 3175);
FORCEPROP 1 LAST PATH I220
J 0
(-3552 3300);
DISPLAY 0.872340 (-3552 3300);
PAINT GREEN (-3552 3300);
DISPLAY INVISIBLE (-3552 3300);
FORCEADD TAP..1
(-3350 3050);
FORCEPROP 3 LASTPIN (-3400 3050) SIG_NAME M_C_CPU1_SB_DQS_DN<5>
J 0
(-3390 3060);
DISPLAY 0.659574 (-3390 3060);
PAINT MONO (-3390 3060);
DISPLAY INVISIBLE (-3390 3060);
FORCEPROP 1 LASTPIN (-3400 3050) BN 5
J 0
(-3412 3058);
DISPLAY 0.489362 (-3412 3058);
PAINT GREEN (-3412 3058);
FORCEPROP 2 LAST CDS_LIB mstr_standard
J 0
(-3350 3050);
DISPLAY 0.723404 (-3350 3050);
PAINT MONO (-3350 3050);
DISPLAY INVISIBLE (-3350 3050);
FORCEPROP 1 LAST BODY_TYPE PLUMBING
J 0
(-3350 3100);
DISPLAY 0.872340 (-3350 3100);
PAINT GREEN (-3350 3100);
DISPLAY INVISIBLE (-3350 3100);
FORCEPROP 1 LAST HDL_TAP TRUE
J 0
(-3025 2925);
DISPLAY 0.872340 (-3025 2925);
DISPLAY INVISIBLE (-3025 2925);
FORCEPROP 1 LAST PATH I221
J 0
(-3352 3050);
DISPLAY 0.872340 (-3352 3050);
PAINT GREEN (-3352 3050);
DISPLAY INVISIBLE (-3352 3050);
FORCEADD TAP..1
(-3350 3250);
FORCEPROP 3 LASTPIN (-3400 3250) SIG_NAME M_C_CPU1_SB_DQS_DN<7>
J 0
(-3390 3260);
DISPLAY 0.659574 (-3390 3260);
PAINT MONO (-3390 3260);
DISPLAY INVISIBLE (-3390 3260);
FORCEPROP 1 LASTPIN (-3400 3250) BN 7
J 0
(-3412 3258);
DISPLAY 0.489362 (-3412 3258);
PAINT GREEN (-3412 3258);
FORCEPROP 2 LAST CDS_LIB mstr_standard
J 0
(-3350 3250);
DISPLAY 0.723404 (-3350 3250);
PAINT MONO (-3350 3250);
DISPLAY INVISIBLE (-3350 3250);
FORCEPROP 1 LAST BODY_TYPE PLUMBING
J 0
(-3350 3300);
DISPLAY 0.872340 (-3350 3300);
PAINT GREEN (-3350 3300);
DISPLAY INVISIBLE (-3350 3300);
FORCEPROP 1 LAST HDL_TAP TRUE
J 0
(-3025 3125);
DISPLAY 0.872340 (-3025 3125);
DISPLAY INVISIBLE (-3025 3125);
FORCEPROP 1 LAST PATH I222
J 0
(-3352 3250);
DISPLAY 0.872340 (-3352 3250);
PAINT GREEN (-3352 3250);
DISPLAY INVISIBLE (-3352 3250);
FORCEADD TAP..1
(-3350 3150);
FORCEPROP 3 LASTPIN (-3400 3150) SIG_NAME M_C_CPU1_SB_DQS_DN<6>
J 0
(-3390 3160);
DISPLAY 0.659574 (-3390 3160);
PAINT MONO (-3390 3160);
DISPLAY INVISIBLE (-3390 3160);
FORCEPROP 1 LASTPIN (-3400 3150) BN 6
J 0
(-3412 3158);
DISPLAY 0.489362 (-3412 3158);
PAINT GREEN (-3412 3158);
FORCEPROP 2 LAST CDS_LIB mstr_standard
J 0
(-3350 3150);
DISPLAY 0.723404 (-3350 3150);
PAINT MONO (-3350 3150);
DISPLAY INVISIBLE (-3350 3150);
FORCEPROP 1 LAST BODY_TYPE PLUMBING
J 0
(-3350 3200);
DISPLAY 0.872340 (-3350 3200);
PAINT GREEN (-3350 3200);
DISPLAY INVISIBLE (-3350 3200);
FORCEPROP 1 LAST HDL_TAP TRUE
J 0
(-3025 3025);
DISPLAY 0.872340 (-3025 3025);
DISPLAY INVISIBLE (-3025 3025);
FORCEPROP 1 LAST PATH I223
J 0
(-3352 3150);
DISPLAY 0.872340 (-3352 3150);
PAINT GREEN (-3352 3150);
DISPLAY INVISIBLE (-3352 3150);
FORCEADD TAP..1
(-3550 3200);
FORCEPROP 3 LASTPIN (-3600 3200) SIG_NAME M_C_CPU1_SB_DQS_DP<6>
J 0
(-3590 3210);
DISPLAY 0.659574 (-3590 3210);
PAINT MONO (-3590 3210);
DISPLAY INVISIBLE (-3590 3210);
FORCEPROP 1 LASTPIN (-3600 3200) BN 6
J 0
(-3612 3208);
DISPLAY 0.489362 (-3612 3208);
PAINT GREEN (-3612 3208);
FORCEPROP 2 LAST CDS_LIB mstr_standard
J 0
(-3550 3200);
DISPLAY 0.723404 (-3550 3200);
PAINT MONO (-3550 3200);
DISPLAY INVISIBLE (-3550 3200);
FORCEPROP 1 LAST BODY_TYPE PLUMBING
J 0
(-3550 3250);
DISPLAY 0.872340 (-3550 3250);
PAINT GREEN (-3550 3250);
DISPLAY INVISIBLE (-3550 3250);
FORCEPROP 1 LAST HDL_TAP TRUE
J 0
(-3225 3075);
DISPLAY 0.872340 (-3225 3075);
DISPLAY INVISIBLE (-3225 3075);
FORCEPROP 1 LAST PATH I224
J 0
(-3552 3200);
DISPLAY 0.872340 (-3552 3200);
PAINT GREEN (-3552 3200);
DISPLAY INVISIBLE (-3552 3200);
FORCEADD TAP..1
(-3550 3100);
FORCEPROP 3 LASTPIN (-3600 3100) SIG_NAME M_C_CPU1_SB_DQS_DP<5>
J 0
(-3590 3110);
DISPLAY 0.659574 (-3590 3110);
PAINT MONO (-3590 3110);
DISPLAY INVISIBLE (-3590 3110);
FORCEPROP 1 LASTPIN (-3600 3100) BN 5
J 0
(-3612 3108);
DISPLAY 0.489362 (-3612 3108);
PAINT GREEN (-3612 3108);
FORCEPROP 2 LAST CDS_LIB mstr_standard
J 0
(-3550 3100);
DISPLAY 0.723404 (-3550 3100);
PAINT MONO (-3550 3100);
DISPLAY INVISIBLE (-3550 3100);
FORCEPROP 1 LAST BODY_TYPE PLUMBING
J 0
(-3550 3150);
DISPLAY 0.872340 (-3550 3150);
PAINT GREEN (-3550 3150);
DISPLAY INVISIBLE (-3550 3150);
FORCEPROP 1 LAST HDL_TAP TRUE
J 0
(-3225 2975);
DISPLAY 0.872340 (-3225 2975);
DISPLAY INVISIBLE (-3225 2975);
FORCEPROP 1 LAST PATH I225
J 0
(-3552 3100);
DISPLAY 0.872340 (-3552 3100);
PAINT GREEN (-3552 3100);
DISPLAY INVISIBLE (-3552 3100);
FORCEADD TAP..1
(-3350 2950);
FORCEPROP 3 LASTPIN (-3400 2950) SIG_NAME M_C_CPU1_SB_DQS_DN<4>
J 0
(-3390 2960);
DISPLAY 0.659574 (-3390 2960);
PAINT MONO (-3390 2960);
DISPLAY INVISIBLE (-3390 2960);
FORCEPROP 1 LASTPIN (-3400 2950) BN 4
J 0
(-3412 2958);
DISPLAY 0.489362 (-3412 2958);
PAINT GREEN (-3412 2958);
FORCEPROP 2 LAST CDS_LIB mstr_standard
J 0
(-3350 2950);
DISPLAY 0.723404 (-3350 2950);
PAINT MONO (-3350 2950);
DISPLAY INVISIBLE (-3350 2950);
FORCEPROP 1 LAST BODY_TYPE PLUMBING
J 0
(-3350 3000);
DISPLAY 0.872340 (-3350 3000);
PAINT GREEN (-3350 3000);
DISPLAY INVISIBLE (-3350 3000);
FORCEPROP 1 LAST HDL_TAP TRUE
J 0
(-3025 2825);
DISPLAY 0.872340 (-3025 2825);
DISPLAY INVISIBLE (-3025 2825);
FORCEPROP 1 LAST PATH I226
J 0
(-3352 2950);
DISPLAY 0.872340 (-3352 2950);
PAINT GREEN (-3352 2950);
DISPLAY INVISIBLE (-3352 2950);
FORCEADD TAP..1
(-3350 2850);
FORCEPROP 3 LASTPIN (-3400 2850) SIG_NAME M_C_CPU1_SB_DQS_DN<3>
J 0
(-3390 2860);
DISPLAY 0.659574 (-3390 2860);
PAINT MONO (-3390 2860);
DISPLAY INVISIBLE (-3390 2860);
FORCEPROP 1 LASTPIN (-3400 2850) BN 3
J 0
(-3412 2858);
DISPLAY 0.489362 (-3412 2858);
PAINT GREEN (-3412 2858);
FORCEPROP 2 LAST CDS_LIB mstr_standard
J 0
(-3350 2850);
DISPLAY 0.723404 (-3350 2850);
PAINT MONO (-3350 2850);
DISPLAY INVISIBLE (-3350 2850);
FORCEPROP 1 LAST BODY_TYPE PLUMBING
J 0
(-3350 2900);
DISPLAY 0.872340 (-3350 2900);
PAINT GREEN (-3350 2900);
DISPLAY INVISIBLE (-3350 2900);
FORCEPROP 1 LAST HDL_TAP TRUE
J 0
(-3025 2725);
DISPLAY 0.872340 (-3025 2725);
DISPLAY INVISIBLE (-3025 2725);
FORCEPROP 1 LAST PATH I227
J 0
(-3352 2850);
DISPLAY 0.872340 (-3352 2850);
PAINT GREEN (-3352 2850);
DISPLAY INVISIBLE (-3352 2850);
FORCEADD TAP..1
(-3550 3000);
FORCEPROP 3 LASTPIN (-3600 3000) SIG_NAME M_C_CPU1_SB_DQS_DP<4>
J 0
(-3590 3010);
DISPLAY 0.659574 (-3590 3010);
PAINT MONO (-3590 3010);
DISPLAY INVISIBLE (-3590 3010);
FORCEPROP 1 LASTPIN (-3600 3000) BN 4
J 0
(-3612 3008);
DISPLAY 0.489362 (-3612 3008);
PAINT GREEN (-3612 3008);
FORCEPROP 2 LAST CDS_LIB mstr_standard
J 0
(-3550 3000);
DISPLAY 0.723404 (-3550 3000);
PAINT MONO (-3550 3000);
DISPLAY INVISIBLE (-3550 3000);
FORCEPROP 1 LAST BODY_TYPE PLUMBING
J 0
(-3550 3050);
DISPLAY 0.872340 (-3550 3050);
PAINT GREEN (-3550 3050);
DISPLAY INVISIBLE (-3550 3050);
FORCEPROP 1 LAST HDL_TAP TRUE
J 0
(-3225 2875);
DISPLAY 0.872340 (-3225 2875);
DISPLAY INVISIBLE (-3225 2875);
FORCEPROP 1 LAST PATH I228
J 0
(-3552 3000);
DISPLAY 0.872340 (-3552 3000);
PAINT GREEN (-3552 3000);
DISPLAY INVISIBLE (-3552 3000);
FORCEADD TAP..1
(-3550 2800);
FORCEPROP 3 LASTPIN (-3600 2800) SIG_NAME M_C_CPU1_SB_DQS_DP<2>
J 0
(-3590 2810);
DISPLAY 0.659574 (-3590 2810);
PAINT MONO (-3590 2810);
DISPLAY INVISIBLE (-3590 2810);
FORCEPROP 1 LASTPIN (-3600 2800) BN 2
J 0
(-3612 2808);
DISPLAY 0.489362 (-3612 2808);
PAINT GREEN (-3612 2808);
FORCEPROP 2 LAST CDS_LIB mstr_standard
J 0
(-3550 2800);
DISPLAY 0.723404 (-3550 2800);
PAINT MONO (-3550 2800);
DISPLAY INVISIBLE (-3550 2800);
FORCEPROP 1 LAST BODY_TYPE PLUMBING
J 0
(-3550 2850);
DISPLAY 0.872340 (-3550 2850);
PAINT GREEN (-3550 2850);
DISPLAY INVISIBLE (-3550 2850);
FORCEPROP 1 LAST HDL_TAP TRUE
J 0
(-3225 2675);
DISPLAY 0.872340 (-3225 2675);
DISPLAY INVISIBLE (-3225 2675);
FORCEPROP 1 LAST PATH I229
J 0
(-3552 2800);
DISPLAY 0.872340 (-3552 2800);
PAINT GREEN (-3552 2800);
DISPLAY INVISIBLE (-3552 2800);
FORCEADD TAP..1
R 2
(-7900 3200);
FORCEPROP 3 LASTPIN (-7850 3200) SIG_NAME M_C_CPU1_SB_CB<0>
J 0
(-7840 3210);
DISPLAY 0.659574 (-7840 3210);
PAINT MONO (-7840 3210);
DISPLAY INVISIBLE (-7840 3210);
FORCEPROP 1 LASTPIN (-7850 3200) BN 0
J 2
(-7838 3208);
DISPLAY 0.489362 (-7838 3208);
PAINT GREEN (-7838 3208);
FORCEPROP 2 LAST CDS_LIB mstr_standard
J 0
(-7900 3200);
DISPLAY 0.723404 (-7900 3200);
PAINT MONO (-7900 3200);
DISPLAY INVISIBLE (-7900 3200);
FORCEPROP 1 LAST BODY_TYPE PLUMBING
J 2
(-7900 3250);
DISPLAY 0.872340 (-7900 3250);
PAINT GREEN (-7900 3250);
DISPLAY INVISIBLE (-7900 3250);
FORCEPROP 1 LAST HDL_TAP TRUE
J 2
(-8225 3075);
DISPLAY 0.872340 (-8225 3075);
DISPLAY INVISIBLE (-8225 3075);
FORCEPROP 1 LAST PATH I23
J 2
(-7898 3200);
DISPLAY 0.872340 (-7898 3200);
PAINT GREEN (-7898 3200);
DISPLAY INVISIBLE (-7898 3200);
FORCEADD TAP..1
(-3550 2900);
FORCEPROP 3 LASTPIN (-3600 2900) SIG_NAME M_C_CPU1_SB_DQS_DP<3>
J 0
(-3590 2910);
DISPLAY 0.659574 (-3590 2910);
PAINT MONO (-3590 2910);
DISPLAY INVISIBLE (-3590 2910);
FORCEPROP 1 LASTPIN (-3600 2900) BN 3
J 0
(-3612 2908);
DISPLAY 0.489362 (-3612 2908);
PAINT GREEN (-3612 2908);
FORCEPROP 2 LAST CDS_LIB mstr_standard
J 0
(-3550 2900);
DISPLAY 0.723404 (-3550 2900);
PAINT MONO (-3550 2900);
DISPLAY INVISIBLE (-3550 2900);
FORCEPROP 1 LAST BODY_TYPE PLUMBING
J 0
(-3550 2950);
DISPLAY 0.872340 (-3550 2950);
PAINT GREEN (-3550 2950);
DISPLAY INVISIBLE (-3550 2950);
FORCEPROP 1 LAST HDL_TAP TRUE
J 0
(-3225 2775);
DISPLAY 0.872340 (-3225 2775);
DISPLAY INVISIBLE (-3225 2775);
FORCEPROP 1 LAST PATH I230
J 0
(-3552 2900);
DISPLAY 0.872340 (-3552 2900);
PAINT GREEN (-3552 2900);
DISPLAY INVISIBLE (-3552 2900);
FORCEADD TAP..1
(-3350 2550);
FORCEPROP 3 LASTPIN (-3400 2550) SIG_NAME M_C_CPU1_SB_DQS_DN<0>
J 0
(-3390 2560);
DISPLAY 0.659574 (-3390 2560);
PAINT MONO (-3390 2560);
DISPLAY INVISIBLE (-3390 2560);
FORCEPROP 1 LASTPIN (-3400 2550) BN 0
J 0
(-3412 2558);
DISPLAY 0.489362 (-3412 2558);
PAINT GREEN (-3412 2558);
FORCEPROP 2 LAST CDS_LIB mstr_standard
J 0
(-3350 2550);
DISPLAY 0.723404 (-3350 2550);
PAINT MONO (-3350 2550);
DISPLAY INVISIBLE (-3350 2550);
FORCEPROP 1 LAST BODY_TYPE PLUMBING
J 0
(-3350 2600);
DISPLAY 0.872340 (-3350 2600);
PAINT GREEN (-3350 2600);
DISPLAY INVISIBLE (-3350 2600);
FORCEPROP 1 LAST HDL_TAP TRUE
J 0
(-3025 2425);
DISPLAY 0.872340 (-3025 2425);
DISPLAY INVISIBLE (-3025 2425);
FORCEPROP 1 LAST PATH I231
J 0
(-3352 2550);
DISPLAY 0.872340 (-3352 2550);
PAINT GREEN (-3352 2550);
DISPLAY INVISIBLE (-3352 2550);
FORCEADD TAP..1
(-3350 2650);
FORCEPROP 3 LASTPIN (-3400 2650) SIG_NAME M_C_CPU1_SB_DQS_DN<1>
J 0
(-3390 2660);
DISPLAY 0.659574 (-3390 2660);
PAINT MONO (-3390 2660);
DISPLAY INVISIBLE (-3390 2660);
FORCEPROP 1 LASTPIN (-3400 2650) BN 1
J 0
(-3412 2658);
DISPLAY 0.489362 (-3412 2658);
PAINT GREEN (-3412 2658);
FORCEPROP 2 LAST CDS_LIB mstr_standard
J 0
(-3350 2650);
DISPLAY 0.723404 (-3350 2650);
PAINT MONO (-3350 2650);
DISPLAY INVISIBLE (-3350 2650);
FORCEPROP 1 LAST BODY_TYPE PLUMBING
J 0
(-3350 2700);
DISPLAY 0.872340 (-3350 2700);
PAINT GREEN (-3350 2700);
DISPLAY INVISIBLE (-3350 2700);
FORCEPROP 1 LAST HDL_TAP TRUE
J 0
(-3025 2525);
DISPLAY 0.872340 (-3025 2525);
DISPLAY INVISIBLE (-3025 2525);
FORCEPROP 1 LAST PATH I232
J 0
(-3352 2650);
DISPLAY 0.872340 (-3352 2650);
PAINT GREEN (-3352 2650);
DISPLAY INVISIBLE (-3352 2650);
FORCEADD TAP..1
(-3350 2750);
FORCEPROP 3 LASTPIN (-3400 2750) SIG_NAME M_C_CPU1_SB_DQS_DN<2>
J 0
(-3390 2760);
DISPLAY 0.659574 (-3390 2760);
PAINT MONO (-3390 2760);
DISPLAY INVISIBLE (-3390 2760);
FORCEPROP 1 LASTPIN (-3400 2750) BN 2
J 0
(-3412 2758);
DISPLAY 0.489362 (-3412 2758);
PAINT GREEN (-3412 2758);
FORCEPROP 2 LAST CDS_LIB mstr_standard
J 0
(-3350 2750);
DISPLAY 0.723404 (-3350 2750);
PAINT MONO (-3350 2750);
DISPLAY INVISIBLE (-3350 2750);
FORCEPROP 1 LAST BODY_TYPE PLUMBING
J 0
(-3350 2800);
DISPLAY 0.872340 (-3350 2800);
PAINT GREEN (-3350 2800);
DISPLAY INVISIBLE (-3350 2800);
FORCEPROP 1 LAST HDL_TAP TRUE
J 0
(-3025 2625);
DISPLAY 0.872340 (-3025 2625);
DISPLAY INVISIBLE (-3025 2625);
FORCEPROP 1 LAST PATH I233
J 0
(-3352 2750);
DISPLAY 0.872340 (-3352 2750);
PAINT GREEN (-3352 2750);
DISPLAY INVISIBLE (-3352 2750);
FORCEADD TAP..1
(-3550 2700);
FORCEPROP 3 LASTPIN (-3600 2700) SIG_NAME M_C_CPU1_SB_DQS_DP<1>
J 0
(-3590 2710);
DISPLAY 0.659574 (-3590 2710);
PAINT MONO (-3590 2710);
DISPLAY INVISIBLE (-3590 2710);
FORCEPROP 1 LASTPIN (-3600 2700) BN 1
J 0
(-3612 2708);
DISPLAY 0.489362 (-3612 2708);
PAINT GREEN (-3612 2708);
FORCEPROP 2 LAST CDS_LIB mstr_standard
J 0
(-3550 2700);
DISPLAY 0.723404 (-3550 2700);
PAINT MONO (-3550 2700);
DISPLAY INVISIBLE (-3550 2700);
FORCEPROP 1 LAST BODY_TYPE PLUMBING
J 0
(-3550 2750);
DISPLAY 0.872340 (-3550 2750);
PAINT GREEN (-3550 2750);
DISPLAY INVISIBLE (-3550 2750);
FORCEPROP 1 LAST HDL_TAP TRUE
J 0
(-3225 2575);
DISPLAY 0.872340 (-3225 2575);
DISPLAY INVISIBLE (-3225 2575);
FORCEPROP 1 LAST PATH I234
J 0
(-3552 2700);
DISPLAY 0.872340 (-3552 2700);
PAINT GREEN (-3552 2700);
DISPLAY INVISIBLE (-3552 2700);
FORCEADD TAP..1
(-3550 2600);
FORCEPROP 3 LASTPIN (-3600 2600) SIG_NAME M_C_CPU1_SB_DQS_DP<0>
J 0
(-3590 2610);
DISPLAY 0.659574 (-3590 2610);
PAINT MONO (-3590 2610);
DISPLAY INVISIBLE (-3590 2610);
FORCEPROP 1 LASTPIN (-3600 2600) BN 0
J 0
(-3612 2608);
DISPLAY 0.489362 (-3612 2608);
PAINT GREEN (-3612 2608);
FORCEPROP 2 LAST CDS_LIB mstr_standard
J 0
(-3550 2600);
DISPLAY 0.723404 (-3550 2600);
PAINT MONO (-3550 2600);
DISPLAY INVISIBLE (-3550 2600);
FORCEPROP 1 LAST BODY_TYPE PLUMBING
J 0
(-3550 2650);
DISPLAY 0.872340 (-3550 2650);
PAINT GREEN (-3550 2650);
DISPLAY INVISIBLE (-3550 2650);
FORCEPROP 1 LAST HDL_TAP TRUE
J 0
(-3225 2475);
DISPLAY 0.872340 (-3225 2475);
DISPLAY INVISIBLE (-3225 2475);
FORCEPROP 1 LAST PATH I235
J 0
(-3552 2600);
DISPLAY 0.872340 (-3552 2600);
PAINT GREEN (-3552 2600);
DISPLAY INVISIBLE (-3552 2600);
FORCEADD SCONN288_DDR506112002KQ..2
(-4500 3550);
FORCEPROP 1 LAST LOCATION J28
J 0
(-5100 4875);
DISPLAY 0.468085 (-5100 4875);
PAINT SKYBLUE (-5100 4875);
FORCEPROP 0 LAST $SEC 2
J 0
(-4950 5025);
DISPLAY 0.680851 (-4950 5025);
PAINT MONO (-4950 5025);
DISPLAY INVISIBLE (-4950 5025);
FORCEPROP 0 LAST CDS_SEC 2
J 0
(-4950 5025);
DISPLAY 1.021277 (-4950 5025);
DISPLAY INVISIBLE (-4950 5025);
FORCEPROP 0 LASTPIN (-3750 3600) $PN 12
J 0
(-3740 3610);
DISPLAY 0.680851 (-3740 3610);
PAINT MONO (-3740 3610);
FORCEPROP 0 LASTPIN (-3750 3650) $PN 11
J 0
(-3740 3660);
DISPLAY 0.680851 (-3740 3660);
PAINT MONO (-3740 3660);
FORCEPROP 0 LASTPIN (-3750 2550) $PN 105
J 0
(-3740 2560);
DISPLAY 0.680851 (-3740 2560);
PAINT MONO (-3740 2560);
FORCEPROP 0 LASTPIN (-3750 2600) $PN 104
J 0
(-3740 2610);
DISPLAY 0.680851 (-3740 2610);
PAINT MONO (-3740 2610);
FORCEPROP 0 LASTPIN (-3750 3700) $PN 23
J 0
(-3740 3710);
DISPLAY 0.680851 (-3740 3710);
PAINT MONO (-3740 3710);
FORCEPROP 0 LASTPIN (-3750 3750) $PN 22
J 0
(-3740 3760);
DISPLAY 0.680851 (-3740 3760);
PAINT MONO (-3740 3760);
FORCEPROP 0 LASTPIN (-3750 2650) $PN 116
J 0
(-3740 2660);
DISPLAY 0.680851 (-3740 2660);
PAINT MONO (-3740 2660);
FORCEPROP 0 LASTPIN (-3750 2700) $PN 115
J 0
(-3740 2710);
DISPLAY 0.680851 (-3740 2710);
PAINT MONO (-3740 2710);
FORCEPROP 0 LASTPIN (-3750 3800) $PN 34
J 0
(-3740 3810);
DISPLAY 0.680851 (-3740 3810);
PAINT MONO (-3740 3810);
FORCEPROP 0 LASTPIN (-3750 3850) $PN 33
J 0
(-3740 3860);
DISPLAY 0.680851 (-3740 3860);
PAINT MONO (-3740 3860);
FORCEPROP 0 LASTPIN (-3750 2750) $PN 127
J 0
(-3740 2760);
DISPLAY 0.680851 (-3740 2760);
PAINT MONO (-3740 2760);
FORCEPROP 0 LASTPIN (-3750 2800) $PN 126
J 0
(-3740 2810);
DISPLAY 0.680851 (-3740 2810);
PAINT MONO (-3740 2810);
FORCEPROP 0 LASTPIN (-3750 3900) $PN 45
J 0
(-3740 3910);
DISPLAY 0.680851 (-3740 3910);
PAINT MONO (-3740 3910);
FORCEPROP 0 LASTPIN (-3750 3950) $PN 44
J 0
(-3740 3960);
DISPLAY 0.680851 (-3740 3960);
PAINT MONO (-3740 3960);
FORCEPROP 0 LASTPIN (-3750 2850) $PN 138
J 0
(-3740 2860);
DISPLAY 0.680851 (-3740 2860);
PAINT MONO (-3740 2860);
FORCEPROP 0 LASTPIN (-3750 2900) $PN 137
J 0
(-3740 2910);
DISPLAY 0.680851 (-3740 2910);
PAINT MONO (-3740 2910);
FORCEPROP 0 LASTPIN (-3750 4000) $PN 56
J 0
(-3740 4010);
DISPLAY 0.680851 (-3740 4010);
PAINT MONO (-3740 4010);
FORCEPROP 0 LASTPIN (-3750 4050) $PN 55
J 0
(-3740 4060);
DISPLAY 0.680851 (-3740 4060);
PAINT MONO (-3740 4060);
FORCEPROP 0 LASTPIN (-3750 2950) $PN 238
J 0
(-3740 2960);
DISPLAY 0.680851 (-3740 2960);
PAINT MONO (-3740 2960);
FORCEPROP 0 LASTPIN (-3750 3000) $PN 239
J 0
(-3740 3010);
DISPLAY 0.680851 (-3740 3010);
PAINT MONO (-3740 3010);
FORCEPROP 0 LASTPIN (-3750 4100) $PN 156
J 0
(-3740 4110);
DISPLAY 0.680851 (-3740 4110);
PAINT MONO (-3740 4110);
FORCEPROP 0 LASTPIN (-3750 4150) $PN 157
J 0
(-3740 4160);
DISPLAY 0.680851 (-3740 4160);
PAINT MONO (-3740 4160);
FORCEPROP 0 LASTPIN (-3750 3050) $PN 249
J 0
(-3740 3060);
DISPLAY 0.680851 (-3740 3060);
PAINT MONO (-3740 3060);
FORCEPROP 0 LASTPIN (-3750 3100) $PN 250
J 0
(-3740 3110);
DISPLAY 0.680851 (-3740 3110);
PAINT MONO (-3740 3110);
FORCEPROP 0 LASTPIN (-3750 4200) $PN 167
J 0
(-3740 4210);
DISPLAY 0.680851 (-3740 4210);
PAINT MONO (-3740 4210);
FORCEPROP 0 LASTPIN (-3750 4250) $PN 168
J 0
(-3740 4260);
DISPLAY 0.680851 (-3740 4260);
PAINT MONO (-3740 4260);
FORCEPROP 0 LASTPIN (-3750 3150) $PN 260
J 0
(-3740 3160);
DISPLAY 0.680851 (-3740 3160);
PAINT MONO (-3740 3160);
FORCEPROP 0 LASTPIN (-3750 3200) $PN 261
J 0
(-3740 3210);
DISPLAY 0.680851 (-3740 3210);
PAINT MONO (-3740 3210);
FORCEPROP 0 LASTPIN (-3750 4300) $PN 178
J 0
(-3740 4310);
DISPLAY 0.680851 (-3740 4310);
PAINT MONO (-3740 4310);
FORCEPROP 0 LASTPIN (-3750 4350) $PN 179
J 0
(-3740 4360);
DISPLAY 0.680851 (-3740 4360);
PAINT MONO (-3740 4360);
FORCEPROP 0 LASTPIN (-3750 3250) $PN 271
J 0
(-3740 3260);
DISPLAY 0.680851 (-3740 3260);
PAINT MONO (-3740 3260);
FORCEPROP 0 LASTPIN (-3750 3300) $PN 272
J 0
(-3740 3310);
DISPLAY 0.680851 (-3740 3310);
PAINT MONO (-3740 3310);
FORCEPROP 0 LASTPIN (-3750 4400) $PN 189
J 0
(-3740 4410);
DISPLAY 0.680851 (-3740 4410);
PAINT MONO (-3740 4410);
FORCEPROP 0 LASTPIN (-3750 4450) $PN 190
J 0
(-3740 4460);
DISPLAY 0.680851 (-3740 4460);
PAINT MONO (-3740 4460);
FORCEPROP 0 LASTPIN (-3750 3350) $PN 282
J 0
(-3740 3360);
DISPLAY 0.680851 (-3740 3360);
PAINT MONO (-3740 3360);
FORCEPROP 0 LASTPIN (-3750 3400) $PN 283
J 0
(-3740 3410);
DISPLAY 0.680851 (-3740 3410);
PAINT MONO (-3740 3410);
FORCEPROP 0 LASTPIN (-3750 4500) $PN 200
J 0
(-3740 4510);
DISPLAY 0.680851 (-3740 4510);
PAINT MONO (-3740 4510);
FORCEPROP 0 LASTPIN (-3750 4550) $PN 201
J 0
(-3740 4560);
DISPLAY 0.680851 (-3740 4560);
PAINT MONO (-3740 4560);
FORCEPROP 0 LASTPIN (-3750 3450) $PN 94
J 0
(-3740 3460);
DISPLAY 0.680851 (-3740 3460);
PAINT MONO (-3740 3460);
FORCEPROP 0 LASTPIN (-3750 3500) $PN 93
J 0
(-3740 3510);
DISPLAY 0.680851 (-3740 3510);
PAINT MONO (-3740 3510);
FORCEPROP 2 LAST PART_TYPE SMLF
J 0
(-4950 4975);
DISPLAY 1.021277 (-4950 4975);
FORCEPROP 1 LAST MATERIAL IO
J 0
(-5100 4725);
DISPLAY 0.468085 (-5100 4725);
PAINT SKYBLUE (-5100 4725);
FORCEPROP 2 LAST VALUE SCONN288_DDR506112002KQ
J 0
(-4950 4925);
DISPLAY 0.489362 (-4950 4925);
PAINT SKYBLUE (-4950 4925);
FORCEPROP 1 LAST PART_NUMBER DFHST8FS479
J 0
(-5100 4800);
DISPLAY 0.468085 (-5100 4800);
PAINT SKYBLUE (-5100 4800);
FORCEPROP 1 LAST CDS_LMAN_SYM_OUTLINE -600,1150,600,-1150
J 0
(-4500 3550);
DISPLAY 0.468085 (-4500 3550);
PAINT GREEN (-4500 3550);
DISPLAY INVISIBLE (-4500 3550);
FORCEPROP 1 LAST PATH I236
J 0
(-4500 3550);
DISPLAY 0.723404 (-4500 3550);
PAINT GREEN (-4500 3550);
DISPLAY INVISIBLE (-4500 3550);
FORCEPROP 1 LAST NEEDS_NO_SIZE TRUE
J 0
(-4500 3550);
DISPLAY 0.723404 (-4500 3550);
PAINT GREEN (-4500 3550);
DISPLAY INVISIBLE (-4500 3550);
FORCEPROP 2 LAST CDS_LIB pure_quanta
J 0
(-4500 3550);
DISPLAY INVISIBLE (-4500 3550);
FORCEADD GND..1
(-2925 5525);
FORCEPROP 3 LASTPIN (-2925 5575) SIG_NAME GND\g
J 0
(-2915 5585);
DISPLAY 0.659574 (-2915 5585);
PAINT MONO (-2915 5585);
DISPLAY INVISIBLE (-2915 5585);
FORCEPROP 2 LAST CDS_LIB pure_quanta_power
J 0
(-2925 5525);
DISPLAY INVISIBLE (-2925 5525);
FORCEPROP 2 LAST BOM_COST MEM
J 0
(-2900 5650);
DISPLAY 0.659574 (-2900 5650);
DISPLAY INVISIBLE (-2900 5650);
FORCEPROP 1 LAST SIZE 1B
J 0
(-2850 5475);
DISPLAY 0.723404 (-2850 5475);
PAINT GREEN (-2850 5475);
DISPLAY INVISIBLE (-2850 5475);
FORCEPROP 1 LAST PATH I237
J 0
(-2850 5525);
DISPLAY 0.872340 (-2850 5525);
PAINT AQUA (-2850 5525);
DISPLAY INVISIBLE (-2850 5525);
FORCEPROP 2 LAST ROOM MEM_EFGH_DECOUPLING_CAPS
J 0
(-2900 5600);
DISPLAY 0.659574 (-2900 5600);
PAINT RED (-2900 5600);
DISPLAY INVISIBLE (-2900 5600);
FORCEPROP 1 LAST HDL_POWER GND
J 0
(-2925 5675);
DISPLAY 0.723404 (-2925 5675);
PAINT GREEN (-2925 5675);
DISPLAY INVISIBLE (-2925 5675);
FORCEADD Q_CAP..1
R 2
(-2925 5875);
FORCEPROP 1 LAST LOCATION C178
J 2
(-2975 5975);
DISPLAY 0.489362 (-2975 5975);
PAINT SKYBLUE (-2975 5975);
FORCEPROP 0 LAST $SEC 1
J 0
(-2975 6025);
DISPLAY 0.680851 (-2975 6025);
PAINT MONO (-2975 6025);
DISPLAY INVISIBLE (-2975 6025);
FORCEPROP 0 LAST CDS_SEC 1
J 0
(-2975 6025);
DISPLAY 0.680851 (-2975 6025);
DISPLAY INVISIBLE (-2975 6025);
FORCEPROP 1 LASTPIN (-2925 5975) $PN 1
J 2
(-2935 5955);
DISPLAY 0.489362 (-2935 5955);
PAINT MONO (-2935 5955);
FORCEPROP 1 LASTPIN (-2925 5775) $PN 2
J 2
(-2935 5755);
DISPLAY 0.489362 (-2935 5755);
PAINT MONO (-2935 5755);
FORCEPROP 1 LAST MATERIAL X6S
J 2
(-2975 5775);
DISPLAY 0.489362 (-2975 5775);
PAINT SKYBLUE (-2975 5775);
FORCEPROP 1 LAST TOLERANCE 10%
J 2
(-2975 5825);
DISPLAY 0.489362 (-2975 5825);
PAINT SKYBLUE (-2975 5825);
FORCEPROP 1 LAST VALUE 10UF
J 2
(-2975 5925);
DISPLAY 0.489362 (-2975 5925);
PAINT SKYBLUE (-2975 5925);
FORCEPROP 1 LAST PART_NUMBER CH6104KEA00
J 2
(-2975 5725);
DISPLAY 0.489362 (-2975 5725);
PAINT SKYBLUE (-2975 5725);
FORCEPROP 1 LAST VOLTAGE 25V
J 2
(-2975 5875);
DISPLAY 0.489362 (-2975 5875);
PAINT SKYBLUE (-2975 5875);
FORCEPROP 1 LAST PACK_TYPE C0805
J 2
(-2975 5675);
DISPLAY 0.489362 (-2975 5675);
PAINT SKYBLUE (-2975 5675);
FORCEPROP 0 LAST BOM_COST MEM
J 2
(-2980 6020);
DISPLAY 0.595745 (-2980 6020);
PAINT MONO (-2980 6020);
DISPLAY INVISIBLE (-2980 6020);
FORCEPROP 2 LAST CDS_LIB pure_quanta
J 0
(-2925 5875);
DISPLAY INVISIBLE (-2925 5875);
FORCEPROP 1 LAST PATH I238
J 2
(-2975 6025);
DISPLAY 0.978723 (-2975 6025);
PAINT WHITE (-2975 6025);
DISPLAY INVISIBLE (-2975 6025);
FORCEPROP 0 LAST ROOM MEM_CH_A_CPU0_DIMM1
J 2
(-2980 6020);
DISPLAY 0.595745 (-2980 6020);
PAINT RED (-2980 6020);
DISPLAY INVISIBLE (-2980 6020);
FORCEADD Q_CAP..1
R 2
(-2350 5875);
FORCEPROP 1 LAST LOCATION C179
J 2
(-2400 5975);
DISPLAY 0.489362 (-2400 5975);
PAINT SKYBLUE (-2400 5975);
FORCEPROP 0 LAST $SEC 1
J 0
(-2400 6025);
DISPLAY 0.680851 (-2400 6025);
PAINT MONO (-2400 6025);
DISPLAY INVISIBLE (-2400 6025);
FORCEPROP 0 LAST CDS_SEC 1
J 0
(-2400 6025);
DISPLAY 0.680851 (-2400 6025);
DISPLAY INVISIBLE (-2400 6025);
FORCEPROP 1 LASTPIN (-2350 5975) $PN 1
J 2
(-2360 5955);
DISPLAY 0.489362 (-2360 5955);
PAINT MONO (-2360 5955);
FORCEPROP 1 LASTPIN (-2350 5775) $PN 2
J 2
(-2360 5755);
DISPLAY 0.489362 (-2360 5755);
PAINT MONO (-2360 5755);
FORCEPROP 1 LAST TOLERANCE 10%
J 2
(-2400 5825);
DISPLAY 0.489362 (-2400 5825);
PAINT SKYBLUE (-2400 5825);
FORCEPROP 1 LAST VALUE 10UF
J 2
(-2400 5925);
DISPLAY 0.489362 (-2400 5925);
PAINT SKYBLUE (-2400 5925);
FORCEPROP 1 LAST VOLTAGE 25V
J 2
(-2400 5875);
DISPLAY 0.489362 (-2400 5875);
PAINT SKYBLUE (-2400 5875);
FORCEPROP 1 LAST PACK_TYPE C0805
J 2
(-2400 5675);
DISPLAY 0.489362 (-2400 5675);
PAINT SKYBLUE (-2400 5675);
FORCEPROP 1 LAST PART_NUMBER CH6104KEA00
J 2
(-2400 5725);
DISPLAY 0.489362 (-2400 5725);
PAINT SKYBLUE (-2400 5725);
FORCEPROP 1 LAST MATERIAL X6S
J 2
(-2400 5775);
DISPLAY 0.489362 (-2400 5775);
PAINT SKYBLUE (-2400 5775);
FORCEPROP 0 LAST BOM_COST MEM
J 2
(-2405 6020);
DISPLAY 0.595745 (-2405 6020);
PAINT MONO (-2405 6020);
DISPLAY INVISIBLE (-2405 6020);
FORCEPROP 2 LAST CDS_LIB pure_quanta
J 0
(-2350 5875);
DISPLAY INVISIBLE (-2350 5875);
FORCEPROP 1 LAST PATH I239
J 2
(-2400 6025);
DISPLAY 0.978723 (-2400 6025);
PAINT WHITE (-2400 6025);
DISPLAY INVISIBLE (-2400 6025);
FORCEPROP 0 LAST ROOM MEM_CH_A_CPU0_DIMM1
J 2
(-2405 6020);
DISPLAY 0.595745 (-2405 6020);
PAINT RED (-2405 6020);
DISPLAY INVISIBLE (-2405 6020);
FORCEADD TAP..1
R 2
(-7900 3300);
FORCEPROP 3 LASTPIN (-7850 3300) SIG_NAME M_C_CPU1_SB_CB<2>
J 0
(-7840 3310);
DISPLAY 0.659574 (-7840 3310);
PAINT MONO (-7840 3310);
DISPLAY INVISIBLE (-7840 3310);
FORCEPROP 1 LASTPIN (-7850 3300) BN 2
J 2
(-7838 3308);
DISPLAY 0.489362 (-7838 3308);
PAINT GREEN (-7838 3308);
FORCEPROP 2 LAST CDS_LIB mstr_standard
J 0
(-7900 3300);
DISPLAY 0.723404 (-7900 3300);
PAINT MONO (-7900 3300);
DISPLAY INVISIBLE (-7900 3300);
FORCEPROP 1 LAST BODY_TYPE PLUMBING
J 2
(-7900 3350);
DISPLAY 0.872340 (-7900 3350);
PAINT GREEN (-7900 3350);
DISPLAY INVISIBLE (-7900 3350);
FORCEPROP 1 LAST HDL_TAP TRUE
J 2
(-8225 3175);
DISPLAY 0.872340 (-8225 3175);
DISPLAY INVISIBLE (-8225 3175);
FORCEPROP 1 LAST PATH I24
J 2
(-7898 3300);
DISPLAY 0.872340 (-7898 3300);
PAINT GREEN (-7898 3300);
DISPLAY INVISIBLE (-7898 3300);
FORCEADD UNIVERSAL_POWER..1
(-2925 6200);
FORCEPROP 3 LASTPIN (-2925 6150) SIG_NAME P12V_MEM_2\g
J 0
(-2915 6160);
DISPLAY 0.659574 (-2915 6160);
PAINT MONO (-2915 6160);
DISPLAY INVISIBLE (-2915 6160);
FORCEPROP 1 LAST HDL_POWER P12V_MEM_2
J 1
(-2925 6250);
DISPLAY 0.489362 (-2925 6250);
PAINT GREEN (-2925 6250);
FORCEPROP 2 LAST CDS_LIB pure_quanta_power
J 0
(-2925 6200);
DISPLAY INVISIBLE (-2925 6200);
FORCEPROP 1 LAST PATH I240
J 0
(-2875 6225);
DISPLAY 0.872340 (-2875 6225);
PAINT AQUA (-2875 6225);
DISPLAY INVISIBLE (-2875 6225);
FORCEADD OFFPAGE..1
(-8525 2700);
FORCEPROP 2 LAST $XR5 102 
J 0
(-9317 2700);
DISPLAY 0.638298 (-9317 2700);
PAINT MONO (-9317 2700);
FORCEPROP 2 LAST $XR4 101 
J 0
(-9197 2700);
DISPLAY 0.638298 (-9197 2700);
PAINT MONO (-9197 2700);
FORCEPROP 2 LAST $XR3 100 
J 0
(-9077 2700);
DISPLAY 0.638298 (-9077 2700);
PAINT MONO (-9077 2700);
FORCEPROP 2 LAST $XR2 98 
J 0
(-8957 2700);
DISPLAY 0.638298 (-8957 2700);
PAINT MONO (-8957 2700);
FORCEPROP 2 LAST $XR1 97 
J 0
(-8867 2700);
DISPLAY 0.638298 (-8867 2700);
PAINT MONO (-8867 2700);
FORCEPROP 2 LAST $XR0 136 
J 0
(-8777 2700);
DISPLAY 0.638298 (-8777 2700);
PAINT MONO (-8777 2700);
FORCEPROP 2 LAST PATH I241
J 0
(-8825 2750);
DISPLAY 0.680851 (-8825 2750);
DISPLAY INVISIBLE (-8825 2750);
FORCEPROP 1 LAST COMMENT_BODY TRUE
J 0
(-8400 2600);
DISPLAY 0.872340 (-8400 2600);
PAINT GREEN (-8400 2600);
DISPLAY INVISIBLE (-8400 2600);
FORCEPROP 1 LAST OFFPAGE TRUE
J 0
(-8200 2575);
DISPLAY 0.872340 (-8200 2575);
PAINT GREEN (-8200 2575);
DISPLAY INVISIBLE (-8200 2575);
FORCEPROP 2 LAST CDS_LIB mstr_standard
J 0
(-8525 2700);
DISPLAY 0.808511 (-8525 2700);
DISPLAY INVISIBLE (-8525 2700);
FORCEADD Q_RES..1
(-7950 2700);
FORCEPROP 1 LAST $LOCATION R1582
J 0
(-8000 2725);
DISPLAY 0.510638 (-8000 2725);
PAINT SKYBLUE (-8000 2725);
FORCEPROP 0 LAST CDS_LOCATION R1582
J 0
(-8000 2800);
DISPLAY 0.680851 (-8000 2800);
DISPLAY INVISIBLE (-8000 2800);
FORCEPROP 0 LAST $SEC 1
J 0
(-8000 2800);
DISPLAY 0.680851 (-8000 2800);
PAINT MONO (-8000 2800);
DISPLAY INVISIBLE (-8000 2800);
FORCEPROP 0 LAST CDS_SEC 1
J 0
(-8000 2800);
DISPLAY 0.680851 (-8000 2800);
DISPLAY INVISIBLE (-8000 2800);
FORCEPROP 1 LASTPIN (-8050 2700) $PN 1
J 0
(-8038 2712);
DISPLAY 0.787234 (-8038 2712);
PAINT MONO (-8038 2712);
FORCEPROP 1 LASTPIN (-7850 2700) $PN 2
J 0
(-7888 2712);
DISPLAY 0.787234 (-7888 2712);
PAINT MONO (-7888 2712);
FORCEPROP 1 LAST VALUE 49.9
J 2
(-7800 2775);
DISPLAY 0.510638 (-7800 2775);
PAINT SKYBLUE (-7800 2775);
FORCEPROP 1 LAST MATERIAL CHIP
J 0
(-7950 2550);
DISPLAY 0.978723 (-7950 2550);
DISPLAY INVISIBLE (-7950 2550);
FORCEPROP 1 LAST PACK_TYPE 0402LF
J 0
(-7700 2550);
DISPLAY 0.978723 (-7700 2550);
DISPLAY INVISIBLE (-7700 2550);
FORCEPROP 1 LAST WATTAGE 1/16W
J 2
(-7975 2550);
DISPLAY 0.978723 (-7975 2550);
DISPLAY INVISIBLE (-7975 2550);
FORCEPROP 1 LAST TOLERANCE 1%
J 0
(-7950 2600);
DISPLAY 0.978723 (-7950 2600);
DISPLAY INVISIBLE (-7950 2600);
FORCEPROP 1 LAST PART_NUMBER CS04992FB07
J 0
(-8000 2800);
DISPLAY 0.978723 (-8000 2800);
DISPLAY INVISIBLE (-8000 2800);
FORCEPROP 1 LAST PATH I242
J 0
(-8000 2850);
DISPLAY 0.978723 (-8000 2850);
PAINT WHITE (-8000 2850);
DISPLAY INVISIBLE (-8000 2850);
FORCEPROP 2 LAST CDS_LIB pure_quanta
J 0
(-7950 2700);
DISPLAY INVISIBLE (-7950 2700);
FORCEADD TAP..1
R 2
(-7900 3250);
FORCEPROP 3 LASTPIN (-7850 3250) SIG_NAME M_C_CPU1_SB_CB<1>
J 0
(-7840 3260);
DISPLAY 0.659574 (-7840 3260);
PAINT MONO (-7840 3260);
DISPLAY INVISIBLE (-7840 3260);
FORCEPROP 1 LASTPIN (-7850 3250) BN 1
J 2
(-7838 3258);
DISPLAY 0.489362 (-7838 3258);
PAINT GREEN (-7838 3258);
FORCEPROP 2 LAST CDS_LIB mstr_standard
J 0
(-7900 3250);
DISPLAY 0.723404 (-7900 3250);
PAINT MONO (-7900 3250);
DISPLAY INVISIBLE (-7900 3250);
FORCEPROP 1 LAST BODY_TYPE PLUMBING
J 2
(-7900 3300);
DISPLAY 0.872340 (-7900 3300);
PAINT GREEN (-7900 3300);
DISPLAY INVISIBLE (-7900 3300);
FORCEPROP 1 LAST HDL_TAP TRUE
J 2
(-8225 3125);
DISPLAY 0.872340 (-8225 3125);
DISPLAY INVISIBLE (-8225 3125);
FORCEPROP 1 LAST PATH I25
J 2
(-7898 3250);
DISPLAY 0.872340 (-7898 3250);
PAINT GREEN (-7898 3250);
DISPLAY INVISIBLE (-7898 3250);
FORCEADD TAP..1
R 2
(-7900 3350);
FORCEPROP 3 LASTPIN (-7850 3350) SIG_NAME M_C_CPU1_SB_CB<3>
J 0
(-7840 3360);
DISPLAY 0.659574 (-7840 3360);
PAINT MONO (-7840 3360);
DISPLAY INVISIBLE (-7840 3360);
FORCEPROP 1 LASTPIN (-7850 3350) BN 3
J 2
(-7838 3358);
DISPLAY 0.489362 (-7838 3358);
PAINT GREEN (-7838 3358);
FORCEPROP 2 LAST CDS_LIB mstr_standard
J 0
(-7900 3350);
DISPLAY 0.723404 (-7900 3350);
PAINT MONO (-7900 3350);
DISPLAY INVISIBLE (-7900 3350);
FORCEPROP 1 LAST BODY_TYPE PLUMBING
J 2
(-7900 3400);
DISPLAY 0.872340 (-7900 3400);
PAINT GREEN (-7900 3400);
DISPLAY INVISIBLE (-7900 3400);
FORCEPROP 1 LAST HDL_TAP TRUE
J 2
(-8225 3225);
DISPLAY 0.872340 (-8225 3225);
DISPLAY INVISIBLE (-8225 3225);
FORCEPROP 1 LAST PATH I26
J 2
(-7898 3350);
DISPLAY 0.872340 (-7898 3350);
PAINT GREEN (-7898 3350);
DISPLAY INVISIBLE (-7898 3350);
FORCEADD TAP..1
R 2
(-7900 3400);
FORCEPROP 3 LASTPIN (-7850 3400) SIG_NAME M_C_CPU1_SB_CB<4>
J 0
(-7840 3410);
DISPLAY 0.659574 (-7840 3410);
PAINT MONO (-7840 3410);
DISPLAY INVISIBLE (-7840 3410);
FORCEPROP 1 LASTPIN (-7850 3400) BN 4
J 2
(-7838 3408);
DISPLAY 0.489362 (-7838 3408);
PAINT GREEN (-7838 3408);
FORCEPROP 2 LAST CDS_LIB mstr_standard
J 0
(-7900 3400);
DISPLAY 0.723404 (-7900 3400);
PAINT MONO (-7900 3400);
DISPLAY INVISIBLE (-7900 3400);
FORCEPROP 1 LAST BODY_TYPE PLUMBING
J 2
(-7900 3450);
DISPLAY 0.872340 (-7900 3450);
PAINT GREEN (-7900 3450);
DISPLAY INVISIBLE (-7900 3450);
FORCEPROP 1 LAST HDL_TAP TRUE
J 2
(-8225 3275);
DISPLAY 0.872340 (-8225 3275);
DISPLAY INVISIBLE (-8225 3275);
FORCEPROP 1 LAST PATH I27
J 2
(-7898 3400);
DISPLAY 0.872340 (-7898 3400);
PAINT GREEN (-7898 3400);
DISPLAY INVISIBLE (-7898 3400);
FORCEADD TAP..1
R 2
(-7900 3450);
FORCEPROP 3 LASTPIN (-7850 3450) SIG_NAME M_C_CPU1_SB_CB<5>
J 0
(-7840 3460);
DISPLAY 0.659574 (-7840 3460);
PAINT MONO (-7840 3460);
DISPLAY INVISIBLE (-7840 3460);
FORCEPROP 1 LASTPIN (-7850 3450) BN 5
J 2
(-7838 3458);
DISPLAY 0.489362 (-7838 3458);
PAINT GREEN (-7838 3458);
FORCEPROP 2 LAST CDS_LIB mstr_standard
J 0
(-7900 3450);
DISPLAY 0.723404 (-7900 3450);
PAINT MONO (-7900 3450);
DISPLAY INVISIBLE (-7900 3450);
FORCEPROP 1 LAST BODY_TYPE PLUMBING
J 2
(-7900 3500);
DISPLAY 0.872340 (-7900 3500);
PAINT GREEN (-7900 3500);
DISPLAY INVISIBLE (-7900 3500);
FORCEPROP 1 LAST HDL_TAP TRUE
J 2
(-8225 3325);
DISPLAY 0.872340 (-8225 3325);
DISPLAY INVISIBLE (-8225 3325);
FORCEPROP 1 LAST PATH I28
J 2
(-7898 3450);
DISPLAY 0.872340 (-7898 3450);
PAINT GREEN (-7898 3450);
DISPLAY INVISIBLE (-7898 3450);
FORCEADD TAP..1
R 2
(-7900 3550);
FORCEPROP 3 LASTPIN (-7850 3550) SIG_NAME M_C_CPU1_SB_CB<7>
J 0
(-7840 3560);
DISPLAY 0.659574 (-7840 3560);
PAINT MONO (-7840 3560);
DISPLAY INVISIBLE (-7840 3560);
FORCEPROP 1 LASTPIN (-7850 3550) BN 7
J 2
(-7838 3558);
DISPLAY 0.489362 (-7838 3558);
PAINT GREEN (-7838 3558);
FORCEPROP 2 LAST CDS_LIB mstr_standard
J 0
(-7900 3550);
DISPLAY 0.723404 (-7900 3550);
PAINT MONO (-7900 3550);
DISPLAY INVISIBLE (-7900 3550);
FORCEPROP 1 LAST BODY_TYPE PLUMBING
J 2
(-7900 3600);
DISPLAY 0.872340 (-7900 3600);
PAINT GREEN (-7900 3600);
DISPLAY INVISIBLE (-7900 3600);
FORCEPROP 1 LAST HDL_TAP TRUE
J 2
(-8225 3425);
DISPLAY 0.872340 (-8225 3425);
DISPLAY INVISIBLE (-8225 3425);
FORCEPROP 1 LAST PATH I29
J 2
(-7898 3550);
DISPLAY 0.872340 (-7898 3550);
PAINT GREEN (-7898 3550);
DISPLAY INVISIBLE (-7898 3550);
FORCEADD TAP..1
R 2
(-7900 3500);
FORCEPROP 3 LASTPIN (-7850 3500) SIG_NAME M_C_CPU1_SB_CB<6>
J 0
(-7840 3510);
DISPLAY 0.659574 (-7840 3510);
PAINT MONO (-7840 3510);
DISPLAY INVISIBLE (-7840 3510);
FORCEPROP 1 LASTPIN (-7850 3500) BN 6
J 2
(-7838 3508);
DISPLAY 0.489362 (-7838 3508);
PAINT GREEN (-7838 3508);
FORCEPROP 2 LAST CDS_LIB mstr_standard
J 0
(-7900 3500);
DISPLAY 0.723404 (-7900 3500);
PAINT MONO (-7900 3500);
DISPLAY INVISIBLE (-7900 3500);
FORCEPROP 1 LAST BODY_TYPE PLUMBING
J 2
(-7900 3550);
DISPLAY 0.872340 (-7900 3550);
PAINT GREEN (-7900 3550);
DISPLAY INVISIBLE (-7900 3550);
FORCEPROP 1 LAST HDL_TAP TRUE
J 2
(-8225 3375);
DISPLAY 0.872340 (-8225 3375);
DISPLAY INVISIBLE (-8225 3375);
FORCEPROP 1 LAST PATH I30
J 2
(-7898 3500);
DISPLAY 0.872340 (-7898 3500);
PAINT GREEN (-7898 3500);
DISPLAY INVISIBLE (-7898 3500);
FORCEADD TAP..1
R 2
(-7900 3650);
FORCEPROP 3 LASTPIN (-7850 3650) SIG_NAME M_C_CPU1_SA_CB<0>
J 0
(-7840 3660);
DISPLAY 0.659574 (-7840 3660);
PAINT MONO (-7840 3660);
DISPLAY INVISIBLE (-7840 3660);
FORCEPROP 1 LASTPIN (-7850 3650) BN 0
J 2
(-7838 3658);
DISPLAY 0.489362 (-7838 3658);
PAINT GREEN (-7838 3658);
FORCEPROP 2 LAST CDS_LIB mstr_standard
J 0
(-7900 3650);
DISPLAY 0.723404 (-7900 3650);
PAINT MONO (-7900 3650);
DISPLAY INVISIBLE (-7900 3650);
FORCEPROP 1 LAST BODY_TYPE PLUMBING
J 2
(-7900 3700);
DISPLAY 0.872340 (-7900 3700);
PAINT GREEN (-7900 3700);
DISPLAY INVISIBLE (-7900 3700);
FORCEPROP 1 LAST HDL_TAP TRUE
J 2
(-8225 3525);
DISPLAY 0.872340 (-8225 3525);
DISPLAY INVISIBLE (-8225 3525);
FORCEPROP 1 LAST PATH I31
J 2
(-7898 3650);
DISPLAY 0.872340 (-7898 3650);
PAINT GREEN (-7898 3650);
DISPLAY INVISIBLE (-7898 3650);
FORCEADD TAP..1
R 2
(-7900 3700);
FORCEPROP 3 LASTPIN (-7850 3700) SIG_NAME M_C_CPU1_SA_CB<1>
J 0
(-7840 3710);
DISPLAY 0.659574 (-7840 3710);
PAINT MONO (-7840 3710);
DISPLAY INVISIBLE (-7840 3710);
FORCEPROP 1 LASTPIN (-7850 3700) BN 1
J 2
(-7838 3708);
DISPLAY 0.489362 (-7838 3708);
PAINT GREEN (-7838 3708);
FORCEPROP 2 LAST CDS_LIB mstr_standard
J 0
(-7900 3700);
DISPLAY 0.723404 (-7900 3700);
PAINT MONO (-7900 3700);
DISPLAY INVISIBLE (-7900 3700);
FORCEPROP 1 LAST BODY_TYPE PLUMBING
J 2
(-7900 3750);
DISPLAY 0.872340 (-7900 3750);
PAINT GREEN (-7900 3750);
DISPLAY INVISIBLE (-7900 3750);
FORCEPROP 1 LAST HDL_TAP TRUE
J 2
(-8225 3575);
DISPLAY 0.872340 (-8225 3575);
DISPLAY INVISIBLE (-8225 3575);
FORCEPROP 1 LAST PATH I32
J 2
(-7898 3700);
DISPLAY 0.872340 (-7898 3700);
PAINT GREEN (-7898 3700);
DISPLAY INVISIBLE (-7898 3700);
FORCEADD TAP..1
R 2
(-7900 3750);
FORCEPROP 3 LASTPIN (-7850 3750) SIG_NAME M_C_CPU1_SA_CB<2>
J 0
(-7840 3760);
DISPLAY 0.659574 (-7840 3760);
PAINT MONO (-7840 3760);
DISPLAY INVISIBLE (-7840 3760);
FORCEPROP 1 LASTPIN (-7850 3750) BN 2
J 2
(-7838 3758);
DISPLAY 0.489362 (-7838 3758);
PAINT GREEN (-7838 3758);
FORCEPROP 2 LAST CDS_LIB mstr_standard
J 0
(-7900 3750);
DISPLAY 0.723404 (-7900 3750);
PAINT MONO (-7900 3750);
DISPLAY INVISIBLE (-7900 3750);
FORCEPROP 1 LAST BODY_TYPE PLUMBING
J 2
(-7900 3800);
DISPLAY 0.872340 (-7900 3800);
PAINT GREEN (-7900 3800);
DISPLAY INVISIBLE (-7900 3800);
FORCEPROP 1 LAST HDL_TAP TRUE
J 2
(-8225 3625);
DISPLAY 0.872340 (-8225 3625);
DISPLAY INVISIBLE (-8225 3625);
FORCEPROP 1 LAST PATH I33
J 2
(-7898 3750);
DISPLAY 0.872340 (-7898 3750);
PAINT GREEN (-7898 3750);
DISPLAY INVISIBLE (-7898 3750);
FORCEADD TAP..1
R 2
(-7900 3800);
FORCEPROP 3 LASTPIN (-7850 3800) SIG_NAME M_C_CPU1_SA_CB<3>
J 0
(-7840 3810);
DISPLAY 0.659574 (-7840 3810);
PAINT MONO (-7840 3810);
DISPLAY INVISIBLE (-7840 3810);
FORCEPROP 1 LASTPIN (-7850 3800) BN 3
J 2
(-7838 3808);
DISPLAY 0.489362 (-7838 3808);
PAINT GREEN (-7838 3808);
FORCEPROP 2 LAST CDS_LIB mstr_standard
J 0
(-7900 3800);
DISPLAY 0.723404 (-7900 3800);
PAINT MONO (-7900 3800);
DISPLAY INVISIBLE (-7900 3800);
FORCEPROP 1 LAST BODY_TYPE PLUMBING
J 2
(-7900 3850);
DISPLAY 0.872340 (-7900 3850);
PAINT GREEN (-7900 3850);
DISPLAY INVISIBLE (-7900 3850);
FORCEPROP 1 LAST HDL_TAP TRUE
J 2
(-8225 3675);
DISPLAY 0.872340 (-8225 3675);
DISPLAY INVISIBLE (-8225 3675);
FORCEPROP 1 LAST PATH I34
J 2
(-7898 3800);
DISPLAY 0.872340 (-7898 3800);
PAINT GREEN (-7898 3800);
DISPLAY INVISIBLE (-7898 3800);
FORCEADD TAP..1
(-6200 2250);
FORCEPROP 3 LASTPIN (-6250 2250) SIG_NAME M_C_CPU1_SB_DQ<1>
J 0
(-6240 2260);
DISPLAY 0.659574 (-6240 2260);
PAINT MONO (-6240 2260);
DISPLAY INVISIBLE (-6240 2260);
FORCEPROP 1 LASTPIN (-6250 2250) BN 1
J 0
(-6262 2258);
DISPLAY 0.489362 (-6262 2258);
PAINT GREEN (-6262 2258);
FORCEPROP 2 LAST CDS_LIB mstr_standard
J 0
(-6200 2250);
DISPLAY 0.723404 (-6200 2250);
PAINT MONO (-6200 2250);
DISPLAY INVISIBLE (-6200 2250);
FORCEPROP 1 LAST BODY_TYPE PLUMBING
J 0
(-6200 2300);
DISPLAY 0.872340 (-6200 2300);
PAINT GREEN (-6200 2300);
DISPLAY INVISIBLE (-6200 2300);
FORCEPROP 1 LAST HDL_TAP TRUE
J 0
(-5875 2125);
DISPLAY 0.872340 (-5875 2125);
DISPLAY INVISIBLE (-5875 2125);
FORCEPROP 1 LAST PATH I35
J 0
(-6202 2250);
DISPLAY 0.872340 (-6202 2250);
PAINT GREEN (-6202 2250);
DISPLAY INVISIBLE (-6202 2250);
FORCEADD TAP..1
(-6200 2200);
FORCEPROP 3 LASTPIN (-6250 2200) SIG_NAME M_C_CPU1_SB_DQ<0>
J 0
(-6240 2210);
DISPLAY 0.659574 (-6240 2210);
PAINT MONO (-6240 2210);
DISPLAY INVISIBLE (-6240 2210);
FORCEPROP 1 LASTPIN (-6250 2200) BN 0
J 0
(-6262 2208);
DISPLAY 0.489362 (-6262 2208);
PAINT GREEN (-6262 2208);
FORCEPROP 2 LAST CDS_LIB mstr_standard
J 0
(-6200 2200);
DISPLAY 0.723404 (-6200 2200);
PAINT MONO (-6200 2200);
DISPLAY INVISIBLE (-6200 2200);
FORCEPROP 1 LAST BODY_TYPE PLUMBING
J 0
(-6200 2250);
DISPLAY 0.872340 (-6200 2250);
PAINT GREEN (-6200 2250);
DISPLAY INVISIBLE (-6200 2250);
FORCEPROP 1 LAST HDL_TAP TRUE
J 0
(-5875 2075);
DISPLAY 0.872340 (-5875 2075);
DISPLAY INVISIBLE (-5875 2075);
FORCEPROP 1 LAST PATH I36
J 0
(-6202 2200);
DISPLAY 0.872340 (-6202 2200);
PAINT GREEN (-6202 2200);
DISPLAY INVISIBLE (-6202 2200);
FORCEADD TAP..1
(-6200 2300);
FORCEPROP 3 LASTPIN (-6250 2300) SIG_NAME M_C_CPU1_SB_DQ<2>
J 0
(-6240 2310);
DISPLAY 0.659574 (-6240 2310);
PAINT MONO (-6240 2310);
DISPLAY INVISIBLE (-6240 2310);
FORCEPROP 1 LASTPIN (-6250 2300) BN 2
J 0
(-6262 2308);
DISPLAY 0.489362 (-6262 2308);
PAINT GREEN (-6262 2308);
FORCEPROP 2 LAST CDS_LIB mstr_standard
J 0
(-6200 2300);
DISPLAY 0.723404 (-6200 2300);
PAINT MONO (-6200 2300);
DISPLAY INVISIBLE (-6200 2300);
FORCEPROP 1 LAST BODY_TYPE PLUMBING
J 0
(-6200 2350);
DISPLAY 0.872340 (-6200 2350);
PAINT GREEN (-6200 2350);
DISPLAY INVISIBLE (-6200 2350);
FORCEPROP 1 LAST HDL_TAP TRUE
J 0
(-5875 2175);
DISPLAY 0.872340 (-5875 2175);
DISPLAY INVISIBLE (-5875 2175);
FORCEPROP 1 LAST PATH I37
J 0
(-6202 2300);
DISPLAY 0.872340 (-6202 2300);
PAINT GREEN (-6202 2300);
DISPLAY INVISIBLE (-6202 2300);
FORCEADD TAP..1
(-6200 2350);
FORCEPROP 3 LASTPIN (-6250 2350) SIG_NAME M_C_CPU1_SB_DQ<3>
J 0
(-6240 2360);
DISPLAY 0.659574 (-6240 2360);
PAINT MONO (-6240 2360);
DISPLAY INVISIBLE (-6240 2360);
FORCEPROP 1 LASTPIN (-6250 2350) BN 3
J 0
(-6262 2358);
DISPLAY 0.489362 (-6262 2358);
PAINT GREEN (-6262 2358);
FORCEPROP 2 LAST CDS_LIB mstr_standard
J 0
(-6200 2350);
DISPLAY 0.723404 (-6200 2350);
PAINT MONO (-6200 2350);
DISPLAY INVISIBLE (-6200 2350);
FORCEPROP 1 LAST BODY_TYPE PLUMBING
J 0
(-6200 2400);
DISPLAY 0.872340 (-6200 2400);
PAINT GREEN (-6200 2400);
DISPLAY INVISIBLE (-6200 2400);
FORCEPROP 1 LAST HDL_TAP TRUE
J 0
(-5875 2225);
DISPLAY 0.872340 (-5875 2225);
DISPLAY INVISIBLE (-5875 2225);
FORCEPROP 1 LAST PATH I38
J 0
(-6202 2350);
DISPLAY 0.872340 (-6202 2350);
PAINT GREEN (-6202 2350);
DISPLAY INVISIBLE (-6202 2350);
FORCEADD TAP..1
(-6200 2400);
FORCEPROP 3 LASTPIN (-6250 2400) SIG_NAME M_C_CPU1_SB_DQ<4>
J 0
(-6240 2410);
DISPLAY 0.659574 (-6240 2410);
PAINT MONO (-6240 2410);
DISPLAY INVISIBLE (-6240 2410);
FORCEPROP 1 LASTPIN (-6250 2400) BN 4
J 0
(-6262 2408);
DISPLAY 0.489362 (-6262 2408);
PAINT GREEN (-6262 2408);
FORCEPROP 2 LAST CDS_LIB mstr_standard
J 0
(-6200 2400);
DISPLAY 0.723404 (-6200 2400);
PAINT MONO (-6200 2400);
DISPLAY INVISIBLE (-6200 2400);
FORCEPROP 1 LAST BODY_TYPE PLUMBING
J 0
(-6200 2450);
DISPLAY 0.872340 (-6200 2450);
PAINT GREEN (-6200 2450);
DISPLAY INVISIBLE (-6200 2450);
FORCEPROP 1 LAST HDL_TAP TRUE
J 0
(-5875 2275);
DISPLAY 0.872340 (-5875 2275);
DISPLAY INVISIBLE (-5875 2275);
FORCEPROP 1 LAST PATH I39
J 0
(-6202 2400);
DISPLAY 0.872340 (-6202 2400);
PAINT GREEN (-6202 2400);
DISPLAY INVISIBLE (-6202 2400);
FORCEADD TAP..1
(-6200 2450);
FORCEPROP 3 LASTPIN (-6250 2450) SIG_NAME M_C_CPU1_SB_DQ<5>
J 0
(-6240 2460);
DISPLAY 0.659574 (-6240 2460);
PAINT MONO (-6240 2460);
DISPLAY INVISIBLE (-6240 2460);
FORCEPROP 1 LASTPIN (-6250 2450) BN 5
J 0
(-6262 2458);
DISPLAY 0.489362 (-6262 2458);
PAINT GREEN (-6262 2458);
FORCEPROP 2 LAST CDS_LIB mstr_standard
J 0
(-6200 2450);
DISPLAY 0.723404 (-6200 2450);
PAINT MONO (-6200 2450);
DISPLAY INVISIBLE (-6200 2450);
FORCEPROP 1 LAST BODY_TYPE PLUMBING
J 0
(-6200 2500);
DISPLAY 0.872340 (-6200 2500);
PAINT GREEN (-6200 2500);
DISPLAY INVISIBLE (-6200 2500);
FORCEPROP 1 LAST HDL_TAP TRUE
J 0
(-5875 2325);
DISPLAY 0.872340 (-5875 2325);
DISPLAY INVISIBLE (-5875 2325);
FORCEPROP 1 LAST PATH I40
J 0
(-6202 2450);
DISPLAY 0.872340 (-6202 2450);
PAINT GREEN (-6202 2450);
DISPLAY INVISIBLE (-6202 2450);
FORCEADD TAP..1
(-6200 2550);
FORCEPROP 3 LASTPIN (-6250 2550) SIG_NAME M_C_CPU1_SB_DQ<7>
J 0
(-6240 2560);
DISPLAY 0.659574 (-6240 2560);
PAINT MONO (-6240 2560);
DISPLAY INVISIBLE (-6240 2560);
FORCEPROP 1 LASTPIN (-6250 2550) BN 7
J 0
(-6262 2558);
DISPLAY 0.489362 (-6262 2558);
PAINT GREEN (-6262 2558);
FORCEPROP 2 LAST CDS_LIB mstr_standard
J 0
(-6200 2550);
DISPLAY 0.723404 (-6200 2550);
PAINT MONO (-6200 2550);
DISPLAY INVISIBLE (-6200 2550);
FORCEPROP 1 LAST BODY_TYPE PLUMBING
J 0
(-6200 2600);
DISPLAY 0.872340 (-6200 2600);
PAINT GREEN (-6200 2600);
DISPLAY INVISIBLE (-6200 2600);
FORCEPROP 1 LAST HDL_TAP TRUE
J 0
(-5875 2425);
DISPLAY 0.872340 (-5875 2425);
DISPLAY INVISIBLE (-5875 2425);
FORCEPROP 1 LAST PATH I41
J 0
(-6202 2550);
DISPLAY 0.872340 (-6202 2550);
PAINT GREEN (-6202 2550);
DISPLAY INVISIBLE (-6202 2550);
FORCEADD TAP..1
(-6200 2500);
FORCEPROP 3 LASTPIN (-6250 2500) SIG_NAME M_C_CPU1_SB_DQ<6>
J 0
(-6240 2510);
DISPLAY 0.659574 (-6240 2510);
PAINT MONO (-6240 2510);
DISPLAY INVISIBLE (-6240 2510);
FORCEPROP 1 LASTPIN (-6250 2500) BN 6
J 0
(-6262 2508);
DISPLAY 0.489362 (-6262 2508);
PAINT GREEN (-6262 2508);
FORCEPROP 2 LAST CDS_LIB mstr_standard
J 0
(-6200 2500);
DISPLAY 0.723404 (-6200 2500);
PAINT MONO (-6200 2500);
DISPLAY INVISIBLE (-6200 2500);
FORCEPROP 1 LAST BODY_TYPE PLUMBING
J 0
(-6200 2550);
DISPLAY 0.872340 (-6200 2550);
PAINT GREEN (-6200 2550);
DISPLAY INVISIBLE (-6200 2550);
FORCEPROP 1 LAST HDL_TAP TRUE
J 0
(-5875 2375);
DISPLAY 0.872340 (-5875 2375);
DISPLAY INVISIBLE (-5875 2375);
FORCEPROP 1 LAST PATH I42
J 0
(-6202 2500);
DISPLAY 0.872340 (-6202 2500);
PAINT GREEN (-6202 2500);
DISPLAY INVISIBLE (-6202 2500);
FORCEADD TAP..1
(-6200 2650);
FORCEPROP 3 LASTPIN (-6250 2650) SIG_NAME M_C_CPU1_SB_DQ<9>
J 0
(-6240 2660);
DISPLAY 0.659574 (-6240 2660);
PAINT MONO (-6240 2660);
DISPLAY INVISIBLE (-6240 2660);
FORCEPROP 1 LASTPIN (-6250 2650) BN 9
J 0
(-6262 2658);
DISPLAY 0.489362 (-6262 2658);
PAINT GREEN (-6262 2658);
FORCEPROP 2 LAST CDS_LIB mstr_standard
J 0
(-6200 2650);
DISPLAY 0.723404 (-6200 2650);
PAINT MONO (-6200 2650);
DISPLAY INVISIBLE (-6200 2650);
FORCEPROP 1 LAST BODY_TYPE PLUMBING
J 0
(-6200 2700);
DISPLAY 0.872340 (-6200 2700);
PAINT GREEN (-6200 2700);
DISPLAY INVISIBLE (-6200 2700);
FORCEPROP 1 LAST HDL_TAP TRUE
J 0
(-5875 2525);
DISPLAY 0.872340 (-5875 2525);
DISPLAY INVISIBLE (-5875 2525);
FORCEPROP 1 LAST PATH I43
J 0
(-6202 2650);
DISPLAY 0.872340 (-6202 2650);
PAINT GREEN (-6202 2650);
DISPLAY INVISIBLE (-6202 2650);
FORCEADD TAP..1
(-6200 2600);
FORCEPROP 3 LASTPIN (-6250 2600) SIG_NAME M_C_CPU1_SB_DQ<8>
J 0
(-6240 2610);
DISPLAY 0.659574 (-6240 2610);
PAINT MONO (-6240 2610);
DISPLAY INVISIBLE (-6240 2610);
FORCEPROP 1 LASTPIN (-6250 2600) BN 8
J 0
(-6262 2608);
DISPLAY 0.489362 (-6262 2608);
PAINT GREEN (-6262 2608);
FORCEPROP 2 LAST CDS_LIB mstr_standard
J 0
(-6200 2600);
DISPLAY 0.723404 (-6200 2600);
PAINT MONO (-6200 2600);
DISPLAY INVISIBLE (-6200 2600);
FORCEPROP 1 LAST BODY_TYPE PLUMBING
J 0
(-6200 2650);
DISPLAY 0.872340 (-6200 2650);
PAINT GREEN (-6200 2650);
DISPLAY INVISIBLE (-6200 2650);
FORCEPROP 1 LAST HDL_TAP TRUE
J 0
(-5875 2475);
DISPLAY 0.872340 (-5875 2475);
DISPLAY INVISIBLE (-5875 2475);
FORCEPROP 1 LAST PATH I44
J 0
(-6202 2600);
DISPLAY 0.872340 (-6202 2600);
PAINT GREEN (-6202 2600);
DISPLAY INVISIBLE (-6202 2600);
FORCEADD TAP..1
(-6200 2750);
FORCEPROP 3 LASTPIN (-6250 2750) SIG_NAME M_C_CPU1_SB_DQ<11>
J 0
(-6240 2760);
DISPLAY 0.659574 (-6240 2760);
PAINT MONO (-6240 2760);
DISPLAY INVISIBLE (-6240 2760);
FORCEPROP 1 LASTPIN (-6250 2750) BN 11
J 0
(-6262 2758);
DISPLAY 0.489362 (-6262 2758);
PAINT GREEN (-6262 2758);
FORCEPROP 2 LAST CDS_LIB mstr_standard
J 0
(-6200 2750);
DISPLAY 0.723404 (-6200 2750);
PAINT MONO (-6200 2750);
DISPLAY INVISIBLE (-6200 2750);
FORCEPROP 1 LAST BODY_TYPE PLUMBING
J 0
(-6200 2800);
DISPLAY 0.872340 (-6200 2800);
PAINT GREEN (-6200 2800);
DISPLAY INVISIBLE (-6200 2800);
FORCEPROP 1 LAST HDL_TAP TRUE
J 0
(-5875 2625);
DISPLAY 0.872340 (-5875 2625);
DISPLAY INVISIBLE (-5875 2625);
FORCEPROP 1 LAST PATH I45
J 0
(-6202 2750);
DISPLAY 0.872340 (-6202 2750);
PAINT GREEN (-6202 2750);
DISPLAY INVISIBLE (-6202 2750);
FORCEADD TAP..1
(-6200 2800);
FORCEPROP 3 LASTPIN (-6250 2800) SIG_NAME M_C_CPU1_SB_DQ<12>
J 0
(-6240 2810);
DISPLAY 0.659574 (-6240 2810);
PAINT MONO (-6240 2810);
DISPLAY INVISIBLE (-6240 2810);
FORCEPROP 1 LASTPIN (-6250 2800) BN 12
J 0
(-6262 2808);
DISPLAY 0.489362 (-6262 2808);
PAINT GREEN (-6262 2808);
FORCEPROP 2 LAST CDS_LIB mstr_standard
J 0
(-6200 2800);
DISPLAY 0.723404 (-6200 2800);
PAINT MONO (-6200 2800);
DISPLAY INVISIBLE (-6200 2800);
FORCEPROP 1 LAST BODY_TYPE PLUMBING
J 0
(-6200 2850);
DISPLAY 0.872340 (-6200 2850);
PAINT GREEN (-6200 2850);
DISPLAY INVISIBLE (-6200 2850);
FORCEPROP 1 LAST HDL_TAP TRUE
J 0
(-5875 2675);
DISPLAY 0.872340 (-5875 2675);
DISPLAY INVISIBLE (-5875 2675);
FORCEPROP 1 LAST PATH I46
J 0
(-6202 2800);
DISPLAY 0.872340 (-6202 2800);
PAINT GREEN (-6202 2800);
DISPLAY INVISIBLE (-6202 2800);
FORCEADD TAP..1
(-6200 2700);
FORCEPROP 3 LASTPIN (-6250 2700) SIG_NAME M_C_CPU1_SB_DQ<10>
J 0
(-6240 2710);
DISPLAY 0.659574 (-6240 2710);
PAINT MONO (-6240 2710);
DISPLAY INVISIBLE (-6240 2710);
FORCEPROP 1 LASTPIN (-6250 2700) BN 10
J 0
(-6262 2708);
DISPLAY 0.489362 (-6262 2708);
PAINT GREEN (-6262 2708);
FORCEPROP 2 LAST CDS_LIB mstr_standard
J 0
(-6200 2700);
DISPLAY 0.723404 (-6200 2700);
PAINT MONO (-6200 2700);
DISPLAY INVISIBLE (-6200 2700);
FORCEPROP 1 LAST BODY_TYPE PLUMBING
J 0
(-6200 2750);
DISPLAY 0.872340 (-6200 2750);
PAINT GREEN (-6200 2750);
DISPLAY INVISIBLE (-6200 2750);
FORCEPROP 1 LAST HDL_TAP TRUE
J 0
(-5875 2575);
DISPLAY 0.872340 (-5875 2575);
DISPLAY INVISIBLE (-5875 2575);
FORCEPROP 1 LAST PATH I47
J 0
(-6202 2700);
DISPLAY 0.872340 (-6202 2700);
PAINT GREEN (-6202 2700);
DISPLAY INVISIBLE (-6202 2700);
FORCEADD TAP..1
(-6200 2850);
FORCEPROP 3 LASTPIN (-6250 2850) SIG_NAME M_C_CPU1_SB_DQ<13>
J 0
(-6240 2860);
DISPLAY 0.659574 (-6240 2860);
PAINT MONO (-6240 2860);
DISPLAY INVISIBLE (-6240 2860);
FORCEPROP 1 LASTPIN (-6250 2850) BN 13
J 0
(-6262 2858);
DISPLAY 0.489362 (-6262 2858);
PAINT GREEN (-6262 2858);
FORCEPROP 2 LAST CDS_LIB mstr_standard
J 0
(-6200 2850);
DISPLAY 0.723404 (-6200 2850);
PAINT MONO (-6200 2850);
DISPLAY INVISIBLE (-6200 2850);
FORCEPROP 1 LAST BODY_TYPE PLUMBING
J 0
(-6200 2900);
DISPLAY 0.872340 (-6200 2900);
PAINT GREEN (-6200 2900);
DISPLAY INVISIBLE (-6200 2900);
FORCEPROP 1 LAST HDL_TAP TRUE
J 0
(-5875 2725);
DISPLAY 0.872340 (-5875 2725);
DISPLAY INVISIBLE (-5875 2725);
FORCEPROP 1 LAST PATH I48
J 0
(-6202 2850);
DISPLAY 0.872340 (-6202 2850);
PAINT GREEN (-6202 2850);
DISPLAY INVISIBLE (-6202 2850);
FORCEADD TAP..1
(-6200 2900);
FORCEPROP 3 LASTPIN (-6250 2900) SIG_NAME M_C_CPU1_SB_DQ<14>
J 0
(-6240 2910);
DISPLAY 0.659574 (-6240 2910);
PAINT MONO (-6240 2910);
DISPLAY INVISIBLE (-6240 2910);
FORCEPROP 1 LASTPIN (-6250 2900) BN 14
J 0
(-6262 2908);
DISPLAY 0.489362 (-6262 2908);
PAINT GREEN (-6262 2908);
FORCEPROP 2 LAST CDS_LIB mstr_standard
J 0
(-6200 2900);
DISPLAY 0.723404 (-6200 2900);
PAINT MONO (-6200 2900);
DISPLAY INVISIBLE (-6200 2900);
FORCEPROP 1 LAST BODY_TYPE PLUMBING
J 0
(-6200 2950);
DISPLAY 0.872340 (-6200 2950);
PAINT GREEN (-6200 2950);
DISPLAY INVISIBLE (-6200 2950);
FORCEPROP 1 LAST HDL_TAP TRUE
J 0
(-5875 2775);
DISPLAY 0.872340 (-5875 2775);
DISPLAY INVISIBLE (-5875 2775);
FORCEPROP 1 LAST PATH I49
J 0
(-6202 2900);
DISPLAY 0.872340 (-6202 2900);
PAINT GREEN (-6202 2900);
DISPLAY INVISIBLE (-6202 2900);
FORCEADD TAP..1
(-6200 2950);
FORCEPROP 3 LASTPIN (-6250 2950) SIG_NAME M_C_CPU1_SB_DQ<15>
J 0
(-6240 2960);
DISPLAY 0.659574 (-6240 2960);
PAINT MONO (-6240 2960);
DISPLAY INVISIBLE (-6240 2960);
FORCEPROP 1 LASTPIN (-6250 2950) BN 15
J 0
(-6262 2958);
DISPLAY 0.489362 (-6262 2958);
PAINT GREEN (-6262 2958);
FORCEPROP 2 LAST CDS_LIB mstr_standard
J 0
(-6200 2950);
DISPLAY 0.723404 (-6200 2950);
PAINT MONO (-6200 2950);
DISPLAY INVISIBLE (-6200 2950);
FORCEPROP 1 LAST BODY_TYPE PLUMBING
J 0
(-6200 3000);
DISPLAY 0.872340 (-6200 3000);
PAINT GREEN (-6200 3000);
DISPLAY INVISIBLE (-6200 3000);
FORCEPROP 1 LAST HDL_TAP TRUE
J 0
(-5875 2825);
DISPLAY 0.872340 (-5875 2825);
DISPLAY INVISIBLE (-5875 2825);
FORCEPROP 1 LAST PATH I50
J 0
(-6202 2950);
DISPLAY 0.872340 (-6202 2950);
PAINT GREEN (-6202 2950);
DISPLAY INVISIBLE (-6202 2950);
FORCEADD TAP..1
(-6200 3050);
FORCEPROP 3 LASTPIN (-6250 3050) SIG_NAME M_C_CPU1_SB_DQ<17>
J 0
(-6240 3060);
DISPLAY 0.659574 (-6240 3060);
PAINT MONO (-6240 3060);
DISPLAY INVISIBLE (-6240 3060);
FORCEPROP 1 LASTPIN (-6250 3050) BN 17
J 0
(-6262 3058);
DISPLAY 0.489362 (-6262 3058);
PAINT GREEN (-6262 3058);
FORCEPROP 2 LAST CDS_LIB mstr_standard
J 0
(-6200 3050);
DISPLAY 0.723404 (-6200 3050);
PAINT MONO (-6200 3050);
DISPLAY INVISIBLE (-6200 3050);
FORCEPROP 1 LAST BODY_TYPE PLUMBING
J 0
(-6200 3100);
DISPLAY 0.872340 (-6200 3100);
PAINT GREEN (-6200 3100);
DISPLAY INVISIBLE (-6200 3100);
FORCEPROP 1 LAST HDL_TAP TRUE
J 0
(-5875 2925);
DISPLAY 0.872340 (-5875 2925);
DISPLAY INVISIBLE (-5875 2925);
FORCEPROP 1 LAST PATH I51
J 0
(-6202 3050);
DISPLAY 0.872340 (-6202 3050);
PAINT GREEN (-6202 3050);
DISPLAY INVISIBLE (-6202 3050);
FORCEADD TAP..1
(-6200 3000);
FORCEPROP 3 LASTPIN (-6250 3000) SIG_NAME M_C_CPU1_SB_DQ<16>
J 0
(-6240 3010);
DISPLAY 0.659574 (-6240 3010);
PAINT MONO (-6240 3010);
DISPLAY INVISIBLE (-6240 3010);
FORCEPROP 1 LASTPIN (-6250 3000) BN 16
J 0
(-6262 3008);
DISPLAY 0.489362 (-6262 3008);
PAINT GREEN (-6262 3008);
FORCEPROP 2 LAST CDS_LIB mstr_standard
J 0
(-6200 3000);
DISPLAY 0.723404 (-6200 3000);
PAINT MONO (-6200 3000);
DISPLAY INVISIBLE (-6200 3000);
FORCEPROP 1 LAST BODY_TYPE PLUMBING
J 0
(-6200 3050);
DISPLAY 0.872340 (-6200 3050);
PAINT GREEN (-6200 3050);
DISPLAY INVISIBLE (-6200 3050);
FORCEPROP 1 LAST HDL_TAP TRUE
J 0
(-5875 2875);
DISPLAY 0.872340 (-5875 2875);
DISPLAY INVISIBLE (-5875 2875);
FORCEPROP 1 LAST PATH I52
J 0
(-6202 3000);
DISPLAY 0.872340 (-6202 3000);
PAINT GREEN (-6202 3000);
DISPLAY INVISIBLE (-6202 3000);
FORCEADD TAP..1
(-6200 3100);
FORCEPROP 3 LASTPIN (-6250 3100) SIG_NAME M_C_CPU1_SB_DQ<18>
J 0
(-6240 3110);
DISPLAY 0.659574 (-6240 3110);
PAINT MONO (-6240 3110);
DISPLAY INVISIBLE (-6240 3110);
FORCEPROP 1 LASTPIN (-6250 3100) BN 18
J 0
(-6262 3108);
DISPLAY 0.489362 (-6262 3108);
PAINT GREEN (-6262 3108);
FORCEPROP 2 LAST CDS_LIB mstr_standard
J 0
(-6200 3100);
DISPLAY 0.723404 (-6200 3100);
PAINT MONO (-6200 3100);
DISPLAY INVISIBLE (-6200 3100);
FORCEPROP 1 LAST BODY_TYPE PLUMBING
J 0
(-6200 3150);
DISPLAY 0.872340 (-6200 3150);
PAINT GREEN (-6200 3150);
DISPLAY INVISIBLE (-6200 3150);
FORCEPROP 1 LAST HDL_TAP TRUE
J 0
(-5875 2975);
DISPLAY 0.872340 (-5875 2975);
DISPLAY INVISIBLE (-5875 2975);
FORCEPROP 1 LAST PATH I53
J 0
(-6202 3100);
DISPLAY 0.872340 (-6202 3100);
PAINT GREEN (-6202 3100);
DISPLAY INVISIBLE (-6202 3100);
FORCEADD TAP..1
(-6200 3150);
FORCEPROP 3 LASTPIN (-6250 3150) SIG_NAME M_C_CPU1_SB_DQ<19>
J 0
(-6240 3160);
DISPLAY 0.659574 (-6240 3160);
PAINT MONO (-6240 3160);
DISPLAY INVISIBLE (-6240 3160);
FORCEPROP 1 LASTPIN (-6250 3150) BN 19
J 0
(-6262 3158);
DISPLAY 0.489362 (-6262 3158);
PAINT GREEN (-6262 3158);
FORCEPROP 2 LAST CDS_LIB mstr_standard
J 0
(-6200 3150);
DISPLAY 0.723404 (-6200 3150);
PAINT MONO (-6200 3150);
DISPLAY INVISIBLE (-6200 3150);
FORCEPROP 1 LAST BODY_TYPE PLUMBING
J 0
(-6200 3200);
DISPLAY 0.872340 (-6200 3200);
PAINT GREEN (-6200 3200);
DISPLAY INVISIBLE (-6200 3200);
FORCEPROP 1 LAST HDL_TAP TRUE
J 0
(-5875 3025);
DISPLAY 0.872340 (-5875 3025);
DISPLAY INVISIBLE (-5875 3025);
FORCEPROP 1 LAST PATH I54
J 0
(-6202 3150);
DISPLAY 0.872340 (-6202 3150);
PAINT GREEN (-6202 3150);
DISPLAY INVISIBLE (-6202 3150);
FORCEADD TAP..1
(-6200 3200);
FORCEPROP 3 LASTPIN (-6250 3200) SIG_NAME M_C_CPU1_SB_DQ<20>
J 0
(-6240 3210);
DISPLAY 0.659574 (-6240 3210);
PAINT MONO (-6240 3210);
DISPLAY INVISIBLE (-6240 3210);
FORCEPROP 1 LASTPIN (-6250 3200) BN 20
J 0
(-6262 3208);
DISPLAY 0.489362 (-6262 3208);
PAINT GREEN (-6262 3208);
FORCEPROP 2 LAST CDS_LIB mstr_standard
J 0
(-6200 3200);
DISPLAY 0.723404 (-6200 3200);
PAINT MONO (-6200 3200);
DISPLAY INVISIBLE (-6200 3200);
FORCEPROP 1 LAST BODY_TYPE PLUMBING
J 0
(-6200 3250);
DISPLAY 0.872340 (-6200 3250);
PAINT GREEN (-6200 3250);
DISPLAY INVISIBLE (-6200 3250);
FORCEPROP 1 LAST HDL_TAP TRUE
J 0
(-5875 3075);
DISPLAY 0.872340 (-5875 3075);
DISPLAY INVISIBLE (-5875 3075);
FORCEPROP 1 LAST PATH I55
J 0
(-6202 3200);
DISPLAY 0.872340 (-6202 3200);
PAINT GREEN (-6202 3200);
DISPLAY INVISIBLE (-6202 3200);
FORCEADD TAP..1
(-6200 3300);
FORCEPROP 3 LASTPIN (-6250 3300) SIG_NAME M_C_CPU1_SB_DQ<22>
J 0
(-6240 3310);
DISPLAY 0.659574 (-6240 3310);
PAINT MONO (-6240 3310);
DISPLAY INVISIBLE (-6240 3310);
FORCEPROP 1 LASTPIN (-6250 3300) BN 22
J 0
(-6262 3308);
DISPLAY 0.489362 (-6262 3308);
PAINT GREEN (-6262 3308);
FORCEPROP 2 LAST CDS_LIB mstr_standard
J 0
(-6200 3300);
DISPLAY 0.723404 (-6200 3300);
PAINT MONO (-6200 3300);
DISPLAY INVISIBLE (-6200 3300);
FORCEPROP 1 LAST BODY_TYPE PLUMBING
J 0
(-6200 3350);
DISPLAY 0.872340 (-6200 3350);
PAINT GREEN (-6200 3350);
DISPLAY INVISIBLE (-6200 3350);
FORCEPROP 1 LAST HDL_TAP TRUE
J 0
(-5875 3175);
DISPLAY 0.872340 (-5875 3175);
DISPLAY INVISIBLE (-5875 3175);
FORCEPROP 1 LAST PATH I56
J 0
(-6202 3300);
DISPLAY 0.872340 (-6202 3300);
PAINT GREEN (-6202 3300);
DISPLAY INVISIBLE (-6202 3300);
FORCEADD TAP..1
(-6200 3250);
FORCEPROP 3 LASTPIN (-6250 3250) SIG_NAME M_C_CPU1_SB_DQ<21>
J 0
(-6240 3260);
DISPLAY 0.659574 (-6240 3260);
PAINT MONO (-6240 3260);
DISPLAY INVISIBLE (-6240 3260);
FORCEPROP 1 LASTPIN (-6250 3250) BN 21
J 0
(-6262 3258);
DISPLAY 0.489362 (-6262 3258);
PAINT GREEN (-6262 3258);
FORCEPROP 2 LAST CDS_LIB mstr_standard
J 0
(-6200 3250);
DISPLAY 0.723404 (-6200 3250);
PAINT MONO (-6200 3250);
DISPLAY INVISIBLE (-6200 3250);
FORCEPROP 1 LAST BODY_TYPE PLUMBING
J 0
(-6200 3300);
DISPLAY 0.872340 (-6200 3300);
PAINT GREEN (-6200 3300);
DISPLAY INVISIBLE (-6200 3300);
FORCEPROP 1 LAST HDL_TAP TRUE
J 0
(-5875 3125);
DISPLAY 0.872340 (-5875 3125);
DISPLAY INVISIBLE (-5875 3125);
FORCEPROP 1 LAST PATH I57
J 0
(-6202 3250);
DISPLAY 0.872340 (-6202 3250);
PAINT GREEN (-6202 3250);
DISPLAY INVISIBLE (-6202 3250);
FORCEADD TAP..1
(-6200 3350);
FORCEPROP 3 LASTPIN (-6250 3350) SIG_NAME M_C_CPU1_SB_DQ<23>
J 0
(-6240 3360);
DISPLAY 0.659574 (-6240 3360);
PAINT MONO (-6240 3360);
DISPLAY INVISIBLE (-6240 3360);
FORCEPROP 1 LASTPIN (-6250 3350) BN 23
J 0
(-6262 3358);
DISPLAY 0.489362 (-6262 3358);
PAINT GREEN (-6262 3358);
FORCEPROP 2 LAST CDS_LIB mstr_standard
J 0
(-6200 3350);
DISPLAY 0.723404 (-6200 3350);
PAINT MONO (-6200 3350);
DISPLAY INVISIBLE (-6200 3350);
FORCEPROP 1 LAST BODY_TYPE PLUMBING
J 0
(-6200 3400);
DISPLAY 0.872340 (-6200 3400);
PAINT GREEN (-6200 3400);
DISPLAY INVISIBLE (-6200 3400);
FORCEPROP 1 LAST HDL_TAP TRUE
J 0
(-5875 3225);
DISPLAY 0.872340 (-5875 3225);
DISPLAY INVISIBLE (-5875 3225);
FORCEPROP 1 LAST PATH I58
J 0
(-6202 3350);
DISPLAY 0.872340 (-6202 3350);
PAINT GREEN (-6202 3350);
DISPLAY INVISIBLE (-6202 3350);
FORCEADD TAP..1
(-6200 3450);
FORCEPROP 3 LASTPIN (-6250 3450) SIG_NAME M_C_CPU1_SB_DQ<25>
J 0
(-6240 3460);
DISPLAY 0.659574 (-6240 3460);
PAINT MONO (-6240 3460);
DISPLAY INVISIBLE (-6240 3460);
FORCEPROP 1 LASTPIN (-6250 3450) BN 25
J 0
(-6262 3458);
DISPLAY 0.489362 (-6262 3458);
PAINT GREEN (-6262 3458);
FORCEPROP 2 LAST CDS_LIB mstr_standard
J 0
(-6200 3450);
DISPLAY 0.723404 (-6200 3450);
PAINT MONO (-6200 3450);
DISPLAY INVISIBLE (-6200 3450);
FORCEPROP 1 LAST BODY_TYPE PLUMBING
J 0
(-6200 3500);
DISPLAY 0.872340 (-6200 3500);
PAINT GREEN (-6200 3500);
DISPLAY INVISIBLE (-6200 3500);
FORCEPROP 1 LAST HDL_TAP TRUE
J 0
(-5875 3325);
DISPLAY 0.872340 (-5875 3325);
DISPLAY INVISIBLE (-5875 3325);
FORCEPROP 1 LAST PATH I59
J 0
(-6202 3450);
DISPLAY 0.872340 (-6202 3450);
PAINT GREEN (-6202 3450);
DISPLAY INVISIBLE (-6202 3450);
FORCEADD VCC_CORE..1
(-8675 3425);
FORCEPROP 3 LASTPIN (-8675 3375) SIG_NAME P3V3_STBY\g
J 0
(-8665 3385);
DISPLAY 0.659574 (-8665 3385);
PAINT MONO (-8665 3385);
DISPLAY INVISIBLE (-8665 3385);
FORCEPROP 1 LAST HDL_POWER P3V3_STBY
J 1
(-8675 3475);
DISPLAY 0.489362 (-8675 3475);
PAINT GREEN (-8675 3475);
FORCEPROP 2 LAST CDS_LIB mstr_symbols
J 0
(-8675 3425);
PAINT MONO (-8675 3425);
DISPLAY INVISIBLE (-8675 3425);
FORCEPROP 1 LAST PATH I6
J 0
(-8625 3450);
DISPLAY 0.872340 (-8625 3450);
PAINT AQUA (-8625 3450);
DISPLAY INVISIBLE (-8625 3450);
FORCEPROP 0 LAST VOLTAGE 3.3
J 0
(-8950 3575);
DISPLAY 1.021277 (-8950 3575);
PAINT SKYBLUE (-8950 3575);
DISPLAY INVISIBLE (-8950 3575);
FORCEPROP 2 LAST ROOM PVCCINFAON_CPU1_CTRL
J 0
(-8675 3525);
DISPLAY 0.808511 (-8675 3525);
PAINT RED (-8675 3525);
DISPLAY INVISIBLE (-8675 3525);
FORCEADD TAP..1
(-6200 3400);
FORCEPROP 3 LASTPIN (-6250 3400) SIG_NAME M_C_CPU1_SB_DQ<24>
J 0
(-6240 3410);
DISPLAY 0.659574 (-6240 3410);
PAINT MONO (-6240 3410);
DISPLAY INVISIBLE (-6240 3410);
FORCEPROP 1 LASTPIN (-6250 3400) BN 24
J 0
(-6262 3408);
DISPLAY 0.489362 (-6262 3408);
PAINT GREEN (-6262 3408);
FORCEPROP 2 LAST CDS_LIB mstr_standard
J 0
(-6200 3400);
DISPLAY 0.723404 (-6200 3400);
PAINT MONO (-6200 3400);
DISPLAY INVISIBLE (-6200 3400);
FORCEPROP 1 LAST BODY_TYPE PLUMBING
J 0
(-6200 3450);
DISPLAY 0.872340 (-6200 3450);
PAINT GREEN (-6200 3450);
DISPLAY INVISIBLE (-6200 3450);
FORCEPROP 1 LAST HDL_TAP TRUE
J 0
(-5875 3275);
DISPLAY 0.872340 (-5875 3275);
DISPLAY INVISIBLE (-5875 3275);
FORCEPROP 1 LAST PATH I60
J 0
(-6202 3400);
DISPLAY 0.872340 (-6202 3400);
PAINT GREEN (-6202 3400);
DISPLAY INVISIBLE (-6202 3400);
FORCEADD TAP..1
(-6200 3500);
FORCEPROP 3 LASTPIN (-6250 3500) SIG_NAME M_C_CPU1_SB_DQ<26>
J 0
(-6240 3510);
DISPLAY 0.659574 (-6240 3510);
PAINT MONO (-6240 3510);
DISPLAY INVISIBLE (-6240 3510);
FORCEPROP 1 LASTPIN (-6250 3500) BN 26
J 0
(-6262 3508);
DISPLAY 0.489362 (-6262 3508);
PAINT GREEN (-6262 3508);
FORCEPROP 2 LAST CDS_LIB mstr_standard
J 0
(-6200 3500);
DISPLAY 0.723404 (-6200 3500);
PAINT MONO (-6200 3500);
DISPLAY INVISIBLE (-6200 3500);
FORCEPROP 1 LAST BODY_TYPE PLUMBING
J 0
(-6200 3550);
DISPLAY 0.872340 (-6200 3550);
PAINT GREEN (-6200 3550);
DISPLAY INVISIBLE (-6200 3550);
FORCEPROP 1 LAST HDL_TAP TRUE
J 0
(-5875 3375);
DISPLAY 0.872340 (-5875 3375);
DISPLAY INVISIBLE (-5875 3375);
FORCEPROP 1 LAST PATH I61
J 0
(-6202 3500);
DISPLAY 0.872340 (-6202 3500);
PAINT GREEN (-6202 3500);
DISPLAY INVISIBLE (-6202 3500);
FORCEADD TAP..1
(-6200 3550);
FORCEPROP 3 LASTPIN (-6250 3550) SIG_NAME M_C_CPU1_SB_DQ<27>
J 0
(-6240 3560);
DISPLAY 0.659574 (-6240 3560);
PAINT MONO (-6240 3560);
DISPLAY INVISIBLE (-6240 3560);
FORCEPROP 1 LASTPIN (-6250 3550) BN 27
J 0
(-6262 3558);
DISPLAY 0.489362 (-6262 3558);
PAINT GREEN (-6262 3558);
FORCEPROP 2 LAST CDS_LIB mstr_standard
J 0
(-6200 3550);
DISPLAY 0.723404 (-6200 3550);
PAINT MONO (-6200 3550);
DISPLAY INVISIBLE (-6200 3550);
FORCEPROP 1 LAST BODY_TYPE PLUMBING
J 0
(-6200 3600);
DISPLAY 0.872340 (-6200 3600);
PAINT GREEN (-6200 3600);
DISPLAY INVISIBLE (-6200 3600);
FORCEPROP 1 LAST HDL_TAP TRUE
J 0
(-5875 3425);
DISPLAY 0.872340 (-5875 3425);
DISPLAY INVISIBLE (-5875 3425);
FORCEPROP 1 LAST PATH I62
J 0
(-6202 3550);
DISPLAY 0.872340 (-6202 3550);
PAINT GREEN (-6202 3550);
DISPLAY INVISIBLE (-6202 3550);
FORCEADD TAP..1
(-6200 3650);
FORCEPROP 3 LASTPIN (-6250 3650) SIG_NAME M_C_CPU1_SB_DQ<29>
J 0
(-6240 3660);
DISPLAY 0.659574 (-6240 3660);
PAINT MONO (-6240 3660);
DISPLAY INVISIBLE (-6240 3660);
FORCEPROP 1 LASTPIN (-6250 3650) BN 29
J 0
(-6262 3658);
DISPLAY 0.489362 (-6262 3658);
PAINT GREEN (-6262 3658);
FORCEPROP 2 LAST CDS_LIB mstr_standard
J 0
(-6200 3650);
DISPLAY 0.723404 (-6200 3650);
PAINT MONO (-6200 3650);
DISPLAY INVISIBLE (-6200 3650);
FORCEPROP 1 LAST BODY_TYPE PLUMBING
J 0
(-6200 3700);
DISPLAY 0.872340 (-6200 3700);
PAINT GREEN (-6200 3700);
DISPLAY INVISIBLE (-6200 3700);
FORCEPROP 1 LAST HDL_TAP TRUE
J 0
(-5875 3525);
DISPLAY 0.872340 (-5875 3525);
DISPLAY INVISIBLE (-5875 3525);
FORCEPROP 1 LAST PATH I63
J 0
(-6202 3650);
DISPLAY 0.872340 (-6202 3650);
PAINT GREEN (-6202 3650);
DISPLAY INVISIBLE (-6202 3650);
FORCEADD TAP..1
(-6200 3700);
FORCEPROP 3 LASTPIN (-6250 3700) SIG_NAME M_C_CPU1_SB_DQ<30>
J 0
(-6240 3710);
DISPLAY 0.659574 (-6240 3710);
PAINT MONO (-6240 3710);
DISPLAY INVISIBLE (-6240 3710);
FORCEPROP 1 LASTPIN (-6250 3700) BN 30
J 0
(-6262 3708);
DISPLAY 0.489362 (-6262 3708);
PAINT GREEN (-6262 3708);
FORCEPROP 2 LAST CDS_LIB mstr_standard
J 0
(-6200 3700);
DISPLAY 0.723404 (-6200 3700);
PAINT MONO (-6200 3700);
DISPLAY INVISIBLE (-6200 3700);
FORCEPROP 1 LAST BODY_TYPE PLUMBING
J 0
(-6200 3750);
DISPLAY 0.872340 (-6200 3750);
PAINT GREEN (-6200 3750);
DISPLAY INVISIBLE (-6200 3750);
FORCEPROP 1 LAST HDL_TAP TRUE
J 0
(-5875 3575);
DISPLAY 0.872340 (-5875 3575);
DISPLAY INVISIBLE (-5875 3575);
FORCEPROP 1 LAST PATH I64
J 0
(-6202 3700);
DISPLAY 0.872340 (-6202 3700);
PAINT GREEN (-6202 3700);
DISPLAY INVISIBLE (-6202 3700);
FORCEADD TAP..1
(-6200 3600);
FORCEPROP 3 LASTPIN (-6250 3600) SIG_NAME M_C_CPU1_SB_DQ<28>
J 0
(-6240 3610);
DISPLAY 0.659574 (-6240 3610);
PAINT MONO (-6240 3610);
DISPLAY INVISIBLE (-6240 3610);
FORCEPROP 1 LASTPIN (-6250 3600) BN 28
J 0
(-6262 3608);
DISPLAY 0.489362 (-6262 3608);
PAINT GREEN (-6262 3608);
FORCEPROP 2 LAST CDS_LIB mstr_standard
J 0
(-6200 3600);
DISPLAY 0.723404 (-6200 3600);
PAINT MONO (-6200 3600);
DISPLAY INVISIBLE (-6200 3600);
FORCEPROP 1 LAST BODY_TYPE PLUMBING
J 0
(-6200 3650);
DISPLAY 0.872340 (-6200 3650);
PAINT GREEN (-6200 3650);
DISPLAY INVISIBLE (-6200 3650);
FORCEPROP 1 LAST HDL_TAP TRUE
J 0
(-5875 3475);
DISPLAY 0.872340 (-5875 3475);
DISPLAY INVISIBLE (-5875 3475);
FORCEPROP 1 LAST PATH I65
J 0
(-6202 3600);
DISPLAY 0.872340 (-6202 3600);
PAINT GREEN (-6202 3600);
DISPLAY INVISIBLE (-6202 3600);
FORCEADD TAP..1
(-6200 3750);
FORCEPROP 3 LASTPIN (-6250 3750) SIG_NAME M_C_CPU1_SB_DQ<31>
J 0
(-6240 3760);
DISPLAY 0.659574 (-6240 3760);
PAINT MONO (-6240 3760);
DISPLAY INVISIBLE (-6240 3760);
FORCEPROP 1 LASTPIN (-6250 3750) BN 31
J 0
(-6262 3758);
DISPLAY 0.489362 (-6262 3758);
PAINT GREEN (-6262 3758);
FORCEPROP 2 LAST CDS_LIB mstr_standard
J 0
(-6200 3750);
DISPLAY 0.723404 (-6200 3750);
PAINT MONO (-6200 3750);
DISPLAY INVISIBLE (-6200 3750);
FORCEPROP 1 LAST BODY_TYPE PLUMBING
J 0
(-6200 3800);
DISPLAY 0.872340 (-6200 3800);
PAINT GREEN (-6200 3800);
DISPLAY INVISIBLE (-6200 3800);
FORCEPROP 1 LAST HDL_TAP TRUE
J 0
(-5875 3625);
DISPLAY 0.872340 (-5875 3625);
DISPLAY INVISIBLE (-5875 3625);
FORCEPROP 1 LAST PATH I66
J 0
(-6202 3750);
DISPLAY 0.872340 (-6202 3750);
PAINT GREEN (-6202 3750);
DISPLAY INVISIBLE (-6202 3750);
FORCEADD OFFPAGE..5
(-8325 3050);
FORCEPROP 2 LAST $XR0 39 
J 0
(-8549 3050);
DISPLAY 0.638298 (-8549 3050);
PAINT MONO (-8549 3050);
FORCEPROP 2 LAST PATH I7
J 0
(-8575 3100);
DISPLAY 1.021277 (-8575 3100);
DISPLAY INVISIBLE (-8575 3100);
FORCEPROP 1 LAST COMMENT_BODY TRUE
J 0
(-8225 2975);
DISPLAY 0.872340 (-8225 2975);
PAINT GREEN (-8225 2975);
DISPLAY INVISIBLE (-8225 2975);
FORCEPROP 1 LAST OFFPAGE TRUE
J 0
(-8000 2925);
DISPLAY 0.872340 (-8000 2925);
PAINT GREEN (-8000 2925);
DISPLAY INVISIBLE (-8000 2925);
FORCEPROP 2 LAST CDS_LIB mstr_standard
J 0
(-8325 3050);
DISPLAY INVISIBLE (-8325 3050);
FORCEADD OFFPAGE..3
(-5600 3800);
FORCEPROP 2 LAST $XR0 39 
J 0
(-5386 3800);
DISPLAY 0.638298 (-5386 3800);
PAINT MONO (-5386 3800);
FORCEPROP 2 LAST PATH I74
J 0
(-5375 3850);
DISPLAY 1.021277 (-5375 3850);
DISPLAY INVISIBLE (-5375 3850);
FORCEPROP 1 LAST COMMENT_BODY TRUE
J 0
(-5650 3700);
DISPLAY 0.872340 (-5650 3700);
PAINT GREEN (-5650 3700);
DISPLAY INVISIBLE (-5650 3700);
FORCEPROP 1 LAST OFFPAGE TRUE
J 0
(-5275 3675);
DISPLAY 0.872340 (-5275 3675);
PAINT GREEN (-5275 3675);
DISPLAY INVISIBLE (-5275 3675);
FORCEPROP 2 LAST CDS_LIB mstr_standard
J 0
(-5600 3800);
DISPLAY 0.723404 (-5600 3800);
PAINT MONO (-5600 3800);
DISPLAY INVISIBLE (-5600 3800);
FORCEADD TAP..1
R 2
(-7900 3850);
FORCEPROP 3 LASTPIN (-7850 3850) SIG_NAME M_C_CPU1_SA_CB<4>
J 0
(-7840 3860);
DISPLAY 0.659574 (-7840 3860);
PAINT MONO (-7840 3860);
DISPLAY INVISIBLE (-7840 3860);
FORCEPROP 1 LASTPIN (-7850 3850) BN 4
J 2
(-7838 3858);
DISPLAY 0.489362 (-7838 3858);
PAINT GREEN (-7838 3858);
FORCEPROP 2 LAST CDS_LIB mstr_standard
J 0
(-7900 3850);
DISPLAY 0.723404 (-7900 3850);
PAINT MONO (-7900 3850);
DISPLAY INVISIBLE (-7900 3850);
FORCEPROP 1 LAST BODY_TYPE PLUMBING
J 2
(-7900 3900);
DISPLAY 0.872340 (-7900 3900);
PAINT GREEN (-7900 3900);
DISPLAY INVISIBLE (-7900 3900);
FORCEPROP 1 LAST HDL_TAP TRUE
J 2
(-8225 3725);
DISPLAY 0.872340 (-8225 3725);
DISPLAY INVISIBLE (-8225 3725);
FORCEPROP 1 LAST PATH I79
J 2
(-7898 3850);
DISPLAY 0.872340 (-7898 3850);
PAINT GREEN (-7898 3850);
DISPLAY INVISIBLE (-7898 3850);
FORCEADD OFFPAGE..1
(-8500 2900);
FORCEPROP 2 LAST $XR0 99 
J 0
(-8721 2900);
DISPLAY 0.638298 (-8721 2900);
PAINT MONO (-8721 2900);
FORCEPROP 2 LAST PATH I8
J 0
(-8750 2950);
DISPLAY 1.021277 (-8750 2950);
DISPLAY INVISIBLE (-8750 2950);
FORCEPROP 1 LAST COMMENT_BODY TRUE
J 0
(-8375 2800);
DISPLAY 0.872340 (-8375 2800);
PAINT GREEN (-8375 2800);
DISPLAY INVISIBLE (-8375 2800);
FORCEPROP 1 LAST OFFPAGE TRUE
J 0
(-8175 2775);
DISPLAY 0.872340 (-8175 2775);
PAINT GREEN (-8175 2775);
DISPLAY INVISIBLE (-8175 2775);
FORCEPROP 2 LAST CDS_LIB mstr_standard
J 0
(-8500 2900);
DISPLAY 0.808511 (-8500 2900);
DISPLAY INVISIBLE (-8500 2900);
FORCEADD TAP..1
R 2
(-7900 3900);
FORCEPROP 3 LASTPIN (-7850 3900) SIG_NAME M_C_CPU1_SA_CB<5>
J 0
(-7840 3910);
DISPLAY 0.659574 (-7840 3910);
PAINT MONO (-7840 3910);
DISPLAY INVISIBLE (-7840 3910);
FORCEPROP 1 LASTPIN (-7850 3900) BN 5
J 2
(-7838 3908);
DISPLAY 0.489362 (-7838 3908);
PAINT GREEN (-7838 3908);
FORCEPROP 2 LAST CDS_LIB mstr_standard
J 0
(-7900 3900);
DISPLAY 0.723404 (-7900 3900);
PAINT MONO (-7900 3900);
DISPLAY INVISIBLE (-7900 3900);
FORCEPROP 1 LAST BODY_TYPE PLUMBING
J 2
(-7900 3950);
DISPLAY 0.872340 (-7900 3950);
PAINT GREEN (-7900 3950);
DISPLAY INVISIBLE (-7900 3950);
FORCEPROP 1 LAST HDL_TAP TRUE
J 2
(-8225 3775);
DISPLAY 0.872340 (-8225 3775);
DISPLAY INVISIBLE (-8225 3775);
FORCEPROP 1 LAST PATH I80
J 2
(-7898 3900);
DISPLAY 0.872340 (-7898 3900);
PAINT GREEN (-7898 3900);
DISPLAY INVISIBLE (-7898 3900);
FORCEADD TAP..1
R 2
(-7900 3950);
FORCEPROP 3 LASTPIN (-7850 3950) SIG_NAME M_C_CPU1_SA_CB<6>
J 0
(-7840 3960);
DISPLAY 0.659574 (-7840 3960);
PAINT MONO (-7840 3960);
DISPLAY INVISIBLE (-7840 3960);
FORCEPROP 1 LASTPIN (-7850 3950) BN 6
J 2
(-7838 3958);
DISPLAY 0.489362 (-7838 3958);
PAINT GREEN (-7838 3958);
FORCEPROP 2 LAST CDS_LIB mstr_standard
J 0
(-7900 3950);
DISPLAY 0.723404 (-7900 3950);
PAINT MONO (-7900 3950);
DISPLAY INVISIBLE (-7900 3950);
FORCEPROP 1 LAST BODY_TYPE PLUMBING
J 2
(-7900 4000);
DISPLAY 0.872340 (-7900 4000);
PAINT GREEN (-7900 4000);
DISPLAY INVISIBLE (-7900 4000);
FORCEPROP 1 LAST HDL_TAP TRUE
J 2
(-8225 3825);
DISPLAY 0.872340 (-8225 3825);
DISPLAY INVISIBLE (-8225 3825);
FORCEPROP 1 LAST PATH I81
J 2
(-7898 3950);
DISPLAY 0.872340 (-7898 3950);
PAINT GREEN (-7898 3950);
DISPLAY INVISIBLE (-7898 3950);
FORCEADD TAP..1
R 2
(-7900 4000);
FORCEPROP 3 LASTPIN (-7850 4000) SIG_NAME M_C_CPU1_SA_CB<7>
J 0
(-7840 4010);
DISPLAY 0.659574 (-7840 4010);
PAINT MONO (-7840 4010);
DISPLAY INVISIBLE (-7840 4010);
FORCEPROP 1 LASTPIN (-7850 4000) BN 7
J 2
(-7838 4008);
DISPLAY 0.489362 (-7838 4008);
PAINT GREEN (-7838 4008);
FORCEPROP 2 LAST CDS_LIB mstr_standard
J 0
(-7900 4000);
DISPLAY 0.723404 (-7900 4000);
PAINT MONO (-7900 4000);
DISPLAY INVISIBLE (-7900 4000);
FORCEPROP 1 LAST BODY_TYPE PLUMBING
J 2
(-7900 4050);
DISPLAY 0.872340 (-7900 4050);
PAINT GREEN (-7900 4050);
DISPLAY INVISIBLE (-7900 4050);
FORCEPROP 1 LAST HDL_TAP TRUE
J 2
(-8225 3875);
DISPLAY 0.872340 (-8225 3875);
DISPLAY INVISIBLE (-8225 3875);
FORCEPROP 1 LAST PATH I82
J 2
(-7898 4000);
DISPLAY 0.872340 (-7898 4000);
PAINT GREEN (-7898 4000);
DISPLAY INVISIBLE (-7898 4000);
FORCEADD TAP..1
R 2
(-7900 4700);
FORCEPROP 3 LASTPIN (-7850 4700) SIG_NAME M_C_CPU1_SB_CA<0>
J 0
(-7840 4710);
DISPLAY 0.659574 (-7840 4710);
PAINT MONO (-7840 4710);
DISPLAY INVISIBLE (-7840 4710);
FORCEPROP 1 LASTPIN (-7850 4700) BN 0
J 2
(-7838 4708);
DISPLAY 0.489362 (-7838 4708);
PAINT GREEN (-7838 4708);
FORCEPROP 2 LAST CDS_LIB mstr_standard
J 0
(-7900 4700);
DISPLAY 0.723404 (-7900 4700);
PAINT MONO (-7900 4700);
DISPLAY INVISIBLE (-7900 4700);
FORCEPROP 1 LAST BODY_TYPE PLUMBING
J 2
(-7900 4750);
DISPLAY 0.872340 (-7900 4750);
PAINT GREEN (-7900 4750);
DISPLAY INVISIBLE (-7900 4750);
FORCEPROP 1 LAST HDL_TAP TRUE
J 2
(-8225 4575);
DISPLAY 0.872340 (-8225 4575);
DISPLAY INVISIBLE (-8225 4575);
FORCEPROP 1 LAST PATH I83
J 2
(-7898 4700);
DISPLAY 0.872340 (-7898 4700);
PAINT GREEN (-7898 4700);
DISPLAY INVISIBLE (-7898 4700);
FORCEADD TAP..1
R 2
(-7900 4800);
FORCEPROP 3 LASTPIN (-7850 4800) SIG_NAME M_C_CPU1_SB_CA<2>
J 0
(-7840 4810);
DISPLAY 0.659574 (-7840 4810);
PAINT MONO (-7840 4810);
DISPLAY INVISIBLE (-7840 4810);
FORCEPROP 1 LASTPIN (-7850 4800) BN 2
J 2
(-7838 4808);
DISPLAY 0.489362 (-7838 4808);
PAINT GREEN (-7838 4808);
FORCEPROP 2 LAST CDS_LIB mstr_standard
J 0
(-7900 4800);
DISPLAY 0.723404 (-7900 4800);
PAINT MONO (-7900 4800);
DISPLAY INVISIBLE (-7900 4800);
FORCEPROP 1 LAST BODY_TYPE PLUMBING
J 2
(-7900 4850);
DISPLAY 0.872340 (-7900 4850);
PAINT GREEN (-7900 4850);
DISPLAY INVISIBLE (-7900 4850);
FORCEPROP 1 LAST HDL_TAP TRUE
J 2
(-8225 4675);
DISPLAY 0.872340 (-8225 4675);
DISPLAY INVISIBLE (-8225 4675);
FORCEPROP 1 LAST PATH I84
J 2
(-7898 4800);
DISPLAY 0.872340 (-7898 4800);
PAINT GREEN (-7898 4800);
DISPLAY INVISIBLE (-7898 4800);
FORCEADD TAP..1
R 2
(-7900 4750);
FORCEPROP 3 LASTPIN (-7850 4750) SIG_NAME M_C_CPU1_SB_CA<1>
J 0
(-7840 4760);
DISPLAY 0.659574 (-7840 4760);
PAINT MONO (-7840 4760);
DISPLAY INVISIBLE (-7840 4760);
FORCEPROP 1 LASTPIN (-7850 4750) BN 1
J 2
(-7838 4758);
DISPLAY 0.489362 (-7838 4758);
PAINT GREEN (-7838 4758);
FORCEPROP 2 LAST CDS_LIB mstr_standard
J 0
(-7900 4750);
DISPLAY 0.723404 (-7900 4750);
PAINT MONO (-7900 4750);
DISPLAY INVISIBLE (-7900 4750);
FORCEPROP 1 LAST BODY_TYPE PLUMBING
J 2
(-7900 4800);
DISPLAY 0.872340 (-7900 4800);
PAINT GREEN (-7900 4800);
DISPLAY INVISIBLE (-7900 4800);
FORCEPROP 1 LAST HDL_TAP TRUE
J 2
(-8225 4625);
DISPLAY 0.872340 (-8225 4625);
DISPLAY INVISIBLE (-8225 4625);
FORCEPROP 1 LAST PATH I85
J 2
(-7898 4750);
DISPLAY 0.872340 (-7898 4750);
PAINT GREEN (-7898 4750);
DISPLAY INVISIBLE (-7898 4750);
FORCEADD TAP..1
R 2
(-7900 4850);
FORCEPROP 3 LASTPIN (-7850 4850) SIG_NAME M_C_CPU1_SB_CA<3>
J 0
(-7840 4860);
DISPLAY 0.659574 (-7840 4860);
PAINT MONO (-7840 4860);
DISPLAY INVISIBLE (-7840 4860);
FORCEPROP 1 LASTPIN (-7850 4850) BN 3
J 2
(-7838 4858);
DISPLAY 0.489362 (-7838 4858);
PAINT GREEN (-7838 4858);
FORCEPROP 2 LAST CDS_LIB mstr_standard
J 0
(-7900 4850);
DISPLAY 0.723404 (-7900 4850);
PAINT MONO (-7900 4850);
DISPLAY INVISIBLE (-7900 4850);
FORCEPROP 1 LAST BODY_TYPE PLUMBING
J 2
(-7900 4900);
DISPLAY 0.872340 (-7900 4900);
PAINT GREEN (-7900 4900);
DISPLAY INVISIBLE (-7900 4900);
FORCEPROP 1 LAST HDL_TAP TRUE
J 2
(-8225 4725);
DISPLAY 0.872340 (-8225 4725);
DISPLAY INVISIBLE (-8225 4725);
FORCEPROP 1 LAST PATH I86
J 2
(-7898 4850);
DISPLAY 0.872340 (-7898 4850);
PAINT GREEN (-7898 4850);
DISPLAY INVISIBLE (-7898 4850);
FORCEADD TAP..1
R 2
(-7900 4900);
FORCEPROP 3 LASTPIN (-7850 4900) SIG_NAME M_C_CPU1_SB_CA<4>
J 0
(-7840 4910);
DISPLAY 0.659574 (-7840 4910);
PAINT MONO (-7840 4910);
DISPLAY INVISIBLE (-7840 4910);
FORCEPROP 1 LASTPIN (-7850 4900) BN 4
J 2
(-7838 4908);
DISPLAY 0.489362 (-7838 4908);
PAINT GREEN (-7838 4908);
FORCEPROP 2 LAST CDS_LIB mstr_standard
J 0
(-7900 4900);
DISPLAY 0.723404 (-7900 4900);
PAINT MONO (-7900 4900);
DISPLAY INVISIBLE (-7900 4900);
FORCEPROP 1 LAST BODY_TYPE PLUMBING
J 2
(-7900 4950);
DISPLAY 0.872340 (-7900 4950);
PAINT GREEN (-7900 4950);
DISPLAY INVISIBLE (-7900 4950);
FORCEPROP 1 LAST HDL_TAP TRUE
J 2
(-8225 4775);
DISPLAY 0.872340 (-8225 4775);
DISPLAY INVISIBLE (-8225 4775);
FORCEPROP 1 LAST PATH I87
J 2
(-7898 4900);
DISPLAY 0.872340 (-7898 4900);
PAINT GREEN (-7898 4900);
DISPLAY INVISIBLE (-7898 4900);
FORCEADD TAP..1
R 2
(-7900 4950);
FORCEPROP 3 LASTPIN (-7850 4950) SIG_NAME M_C_CPU1_SB_CA<5>
J 0
(-7840 4960);
DISPLAY 0.659574 (-7840 4960);
PAINT MONO (-7840 4960);
DISPLAY INVISIBLE (-7840 4960);
FORCEPROP 1 LASTPIN (-7850 4950) BN 5
J 2
(-7838 4958);
DISPLAY 0.489362 (-7838 4958);
PAINT GREEN (-7838 4958);
FORCEPROP 2 LAST CDS_LIB mstr_standard
J 0
(-7900 4950);
DISPLAY 0.723404 (-7900 4950);
PAINT MONO (-7900 4950);
DISPLAY INVISIBLE (-7900 4950);
FORCEPROP 1 LAST BODY_TYPE PLUMBING
J 2
(-7900 5000);
DISPLAY 0.872340 (-7900 5000);
PAINT GREEN (-7900 5000);
DISPLAY INVISIBLE (-7900 5000);
FORCEPROP 1 LAST HDL_TAP TRUE
J 2
(-8225 4825);
DISPLAY 0.872340 (-8225 4825);
DISPLAY INVISIBLE (-8225 4825);
FORCEPROP 1 LAST PATH I88
J 2
(-7898 4950);
DISPLAY 0.872340 (-7898 4950);
PAINT GREEN (-7898 4950);
DISPLAY INVISIBLE (-7898 4950);
FORCEADD TAP..1
R 2
(-7900 5000);
FORCEPROP 3 LASTPIN (-7850 5000) SIG_NAME M_C_CPU1_SB_CA<6>
J 0
(-7840 5010);
DISPLAY 0.659574 (-7840 5010);
PAINT MONO (-7840 5010);
DISPLAY INVISIBLE (-7840 5010);
FORCEPROP 1 LASTPIN (-7850 5000) BN 6
J 2
(-7838 5008);
DISPLAY 0.489362 (-7838 5008);
PAINT GREEN (-7838 5008);
FORCEPROP 2 LAST CDS_LIB mstr_standard
J 0
(-7900 5000);
DISPLAY 0.723404 (-7900 5000);
PAINT MONO (-7900 5000);
DISPLAY INVISIBLE (-7900 5000);
FORCEPROP 1 LAST BODY_TYPE PLUMBING
J 2
(-7900 5050);
DISPLAY 0.872340 (-7900 5050);
PAINT GREEN (-7900 5050);
DISPLAY INVISIBLE (-7900 5050);
FORCEPROP 1 LAST HDL_TAP TRUE
J 2
(-8225 4875);
DISPLAY 0.872340 (-8225 4875);
DISPLAY INVISIBLE (-8225 4875);
FORCEPROP 1 LAST PATH I89
J 2
(-7898 5000);
DISPLAY 0.872340 (-7898 5000);
PAINT GREEN (-7898 5000);
DISPLAY INVISIBLE (-7898 5000);
FORCEADD OFFPAGE..1
(-8325 3100);
FORCEPROP 2 LAST $XR0 39 
J 0
(-8546 3100);
DISPLAY 0.638298 (-8546 3100);
PAINT MONO (-8546 3100);
FORCEPROP 2 LAST PATH I9
J 0
(-8525 3150);
DISPLAY 1.021277 (-8525 3150);
DISPLAY INVISIBLE (-8525 3150);
FORCEPROP 1 LAST COMMENT_BODY TRUE
J 0
(-8200 3000);
DISPLAY 0.872340 (-8200 3000);
PAINT GREEN (-8200 3000);
DISPLAY INVISIBLE (-8200 3000);
FORCEPROP 1 LAST OFFPAGE TRUE
J 0
(-8000 2975);
DISPLAY 0.872340 (-8000 2975);
PAINT GREEN (-8000 2975);
DISPLAY INVISIBLE (-8000 2975);
FORCEPROP 2 LAST CDS_LIB mstr_standard
J 0
(-8325 3100);
DISPLAY 0.808511 (-8325 3100);
DISPLAY INVISIBLE (-8325 3100);
FORCEADD TAP..1
R 2
(-7900 5100);
FORCEPROP 3 LASTPIN (-7850 5100) SIG_NAME M_C_CPU1_SA_CA<0>
J 0
(-7840 5110);
DISPLAY 0.659574 (-7840 5110);
PAINT MONO (-7840 5110);
DISPLAY INVISIBLE (-7840 5110);
FORCEPROP 1 LASTPIN (-7850 5100) BN 0
J 2
(-7838 5108);
DISPLAY 0.489362 (-7838 5108);
PAINT GREEN (-7838 5108);
FORCEPROP 2 LAST CDS_LIB mstr_standard
J 0
(-7900 5100);
DISPLAY 0.723404 (-7900 5100);
PAINT MONO (-7900 5100);
DISPLAY INVISIBLE (-7900 5100);
FORCEPROP 1 LAST BODY_TYPE PLUMBING
J 2
(-7900 5150);
DISPLAY 0.872340 (-7900 5150);
PAINT GREEN (-7900 5150);
DISPLAY INVISIBLE (-7900 5150);
FORCEPROP 1 LAST HDL_TAP TRUE
J 2
(-8225 4975);
DISPLAY 0.872340 (-8225 4975);
DISPLAY INVISIBLE (-8225 4975);
FORCEPROP 1 LAST PATH I90
J 2
(-7898 5100);
DISPLAY 0.872340 (-7898 5100);
PAINT GREEN (-7898 5100);
DISPLAY INVISIBLE (-7898 5100);
FORCEADD TAP..1
R 2
(-7900 5150);
FORCEPROP 3 LASTPIN (-7850 5150) SIG_NAME M_C_CPU1_SA_CA<1>
J 0
(-7840 5160);
DISPLAY 0.659574 (-7840 5160);
PAINT MONO (-7840 5160);
DISPLAY INVISIBLE (-7840 5160);
FORCEPROP 1 LASTPIN (-7850 5150) BN 1
J 2
(-7838 5158);
DISPLAY 0.489362 (-7838 5158);
PAINT GREEN (-7838 5158);
FORCEPROP 2 LAST CDS_LIB mstr_standard
J 0
(-7900 5150);
DISPLAY 0.723404 (-7900 5150);
PAINT MONO (-7900 5150);
DISPLAY INVISIBLE (-7900 5150);
FORCEPROP 1 LAST BODY_TYPE PLUMBING
J 2
(-7900 5200);
DISPLAY 0.872340 (-7900 5200);
PAINT GREEN (-7900 5200);
DISPLAY INVISIBLE (-7900 5200);
FORCEPROP 1 LAST HDL_TAP TRUE
J 2
(-8225 5025);
DISPLAY 0.872340 (-8225 5025);
DISPLAY INVISIBLE (-8225 5025);
FORCEPROP 1 LAST PATH I91
J 2
(-7898 5150);
DISPLAY 0.872340 (-7898 5150);
PAINT GREEN (-7898 5150);
DISPLAY INVISIBLE (-7898 5150);
FORCEADD TAP..1
R 2
(-7900 5200);
FORCEPROP 3 LASTPIN (-7850 5200) SIG_NAME M_C_CPU1_SA_CA<2>
J 0
(-7840 5210);
DISPLAY 0.659574 (-7840 5210);
PAINT MONO (-7840 5210);
DISPLAY INVISIBLE (-7840 5210);
FORCEPROP 1 LASTPIN (-7850 5200) BN 2
J 2
(-7838 5208);
DISPLAY 0.489362 (-7838 5208);
PAINT GREEN (-7838 5208);
FORCEPROP 2 LAST CDS_LIB mstr_standard
J 0
(-7900 5200);
DISPLAY 0.723404 (-7900 5200);
PAINT MONO (-7900 5200);
DISPLAY INVISIBLE (-7900 5200);
FORCEPROP 1 LAST BODY_TYPE PLUMBING
J 2
(-7900 5250);
DISPLAY 0.872340 (-7900 5250);
PAINT GREEN (-7900 5250);
DISPLAY INVISIBLE (-7900 5250);
FORCEPROP 1 LAST HDL_TAP TRUE
J 2
(-8225 5075);
DISPLAY 0.872340 (-8225 5075);
DISPLAY INVISIBLE (-8225 5075);
FORCEPROP 1 LAST PATH I92
J 2
(-7898 5200);
DISPLAY 0.872340 (-7898 5200);
PAINT GREEN (-7898 5200);
DISPLAY INVISIBLE (-7898 5200);
FORCEADD TAP..1
R 2
(-7900 5250);
FORCEPROP 3 LASTPIN (-7850 5250) SIG_NAME M_C_CPU1_SA_CA<3>
J 0
(-7840 5260);
DISPLAY 0.659574 (-7840 5260);
PAINT MONO (-7840 5260);
DISPLAY INVISIBLE (-7840 5260);
FORCEPROP 1 LASTPIN (-7850 5250) BN 3
J 2
(-7838 5258);
DISPLAY 0.489362 (-7838 5258);
PAINT GREEN (-7838 5258);
FORCEPROP 2 LAST CDS_LIB mstr_standard
J 0
(-7900 5250);
DISPLAY 0.723404 (-7900 5250);
PAINT MONO (-7900 5250);
DISPLAY INVISIBLE (-7900 5250);
FORCEPROP 1 LAST BODY_TYPE PLUMBING
J 2
(-7900 5300);
DISPLAY 0.872340 (-7900 5300);
PAINT GREEN (-7900 5300);
DISPLAY INVISIBLE (-7900 5300);
FORCEPROP 1 LAST HDL_TAP TRUE
J 2
(-8225 5125);
DISPLAY 0.872340 (-8225 5125);
DISPLAY INVISIBLE (-8225 5125);
FORCEPROP 1 LAST PATH I93
J 2
(-7898 5250);
DISPLAY 0.872340 (-7898 5250);
PAINT GREEN (-7898 5250);
DISPLAY INVISIBLE (-7898 5250);
FORCEADD TAP..1
R 2
(-7900 5350);
FORCEPROP 3 LASTPIN (-7850 5350) SIG_NAME M_C_CPU1_SA_CA<5>
J 0
(-7840 5360);
DISPLAY 0.659574 (-7840 5360);
PAINT MONO (-7840 5360);
DISPLAY INVISIBLE (-7840 5360);
FORCEPROP 1 LASTPIN (-7850 5350) BN 5
J 2
(-7838 5358);
DISPLAY 0.489362 (-7838 5358);
PAINT GREEN (-7838 5358);
FORCEPROP 2 LAST CDS_LIB mstr_standard
J 0
(-7900 5350);
DISPLAY 0.723404 (-7900 5350);
PAINT MONO (-7900 5350);
DISPLAY INVISIBLE (-7900 5350);
FORCEPROP 1 LAST BODY_TYPE PLUMBING
J 2
(-7900 5400);
DISPLAY 0.872340 (-7900 5400);
PAINT GREEN (-7900 5400);
DISPLAY INVISIBLE (-7900 5400);
FORCEPROP 1 LAST HDL_TAP TRUE
J 2
(-8225 5225);
DISPLAY 0.872340 (-8225 5225);
DISPLAY INVISIBLE (-8225 5225);
FORCEPROP 1 LAST PATH I94
J 2
(-7898 5350);
DISPLAY 0.872340 (-7898 5350);
PAINT GREEN (-7898 5350);
DISPLAY INVISIBLE (-7898 5350);
FORCEADD TAP..1
R 2
(-7900 5300);
FORCEPROP 3 LASTPIN (-7850 5300) SIG_NAME M_C_CPU1_SA_CA<4>
J 0
(-7840 5310);
DISPLAY 0.659574 (-7840 5310);
PAINT MONO (-7840 5310);
DISPLAY INVISIBLE (-7840 5310);
FORCEPROP 1 LASTPIN (-7850 5300) BN 4
J 2
(-7838 5308);
DISPLAY 0.489362 (-7838 5308);
PAINT GREEN (-7838 5308);
FORCEPROP 2 LAST CDS_LIB mstr_standard
J 0
(-7900 5300);
DISPLAY 0.723404 (-7900 5300);
PAINT MONO (-7900 5300);
DISPLAY INVISIBLE (-7900 5300);
FORCEPROP 1 LAST BODY_TYPE PLUMBING
J 2
(-7900 5350);
DISPLAY 0.872340 (-7900 5350);
PAINT GREEN (-7900 5350);
DISPLAY INVISIBLE (-7900 5350);
FORCEPROP 1 LAST HDL_TAP TRUE
J 2
(-8225 5175);
DISPLAY 0.872340 (-8225 5175);
DISPLAY INVISIBLE (-8225 5175);
FORCEPROP 1 LAST PATH I95
J 2
(-7898 5300);
DISPLAY 0.872340 (-7898 5300);
PAINT GREEN (-7898 5300);
DISPLAY INVISIBLE (-7898 5300);
FORCEADD TAP..1
R 2
(-7900 5400);
FORCEPROP 3 LASTPIN (-7850 5400) SIG_NAME M_C_CPU1_SA_CA<6>
J 0
(-7840 5410);
DISPLAY 0.659574 (-7840 5410);
PAINT MONO (-7840 5410);
DISPLAY INVISIBLE (-7840 5410);
FORCEPROP 1 LASTPIN (-7850 5400) BN 6
J 2
(-7838 5408);
DISPLAY 0.489362 (-7838 5408);
PAINT GREEN (-7838 5408);
FORCEPROP 2 LAST CDS_LIB mstr_standard
J 0
(-7900 5400);
DISPLAY 0.723404 (-7900 5400);
PAINT MONO (-7900 5400);
DISPLAY INVISIBLE (-7900 5400);
FORCEPROP 1 LAST BODY_TYPE PLUMBING
J 2
(-7900 5450);
DISPLAY 0.872340 (-7900 5450);
PAINT GREEN (-7900 5450);
DISPLAY INVISIBLE (-7900 5450);
FORCEPROP 1 LAST HDL_TAP TRUE
J 2
(-8225 5275);
DISPLAY 0.872340 (-8225 5275);
DISPLAY INVISIBLE (-8225 5275);
FORCEPROP 1 LAST PATH I96
J 2
(-7898 5400);
DISPLAY 0.872340 (-7898 5400);
PAINT GREEN (-7898 5400);
DISPLAY INVISIBLE (-7898 5400);
FORCEADD TAP..1
(-6200 3850);
FORCEPROP 3 LASTPIN (-6250 3850) SIG_NAME M_C_CPU1_SA_DQ<0>
J 0
(-6240 3860);
DISPLAY 0.659574 (-6240 3860);
PAINT MONO (-6240 3860);
DISPLAY INVISIBLE (-6240 3860);
FORCEPROP 1 LASTPIN (-6250 3850) BN 0
J 0
(-6262 3858);
DISPLAY 0.489362 (-6262 3858);
PAINT GREEN (-6262 3858);
FORCEPROP 2 LAST CDS_LIB mstr_standard
J 0
(-6200 3850);
DISPLAY 0.723404 (-6200 3850);
PAINT MONO (-6200 3850);
DISPLAY INVISIBLE (-6200 3850);
FORCEPROP 1 LAST BODY_TYPE PLUMBING
J 0
(-6200 3900);
DISPLAY 0.872340 (-6200 3900);
PAINT GREEN (-6200 3900);
DISPLAY INVISIBLE (-6200 3900);
FORCEPROP 1 LAST HDL_TAP TRUE
J 0
(-5875 3725);
DISPLAY 0.872340 (-5875 3725);
DISPLAY INVISIBLE (-5875 3725);
FORCEPROP 1 LAST PATH I97
J 0
(-6202 3850);
DISPLAY 0.872340 (-6202 3850);
PAINT GREEN (-6202 3850);
DISPLAY INVISIBLE (-6202 3850);
FORCEADD TAP..1
(-6200 3950);
FORCEPROP 3 LASTPIN (-6250 3950) SIG_NAME M_C_CPU1_SA_DQ<2>
J 0
(-6240 3960);
DISPLAY 0.659574 (-6240 3960);
PAINT MONO (-6240 3960);
DISPLAY INVISIBLE (-6240 3960);
FORCEPROP 1 LASTPIN (-6250 3950) BN 2
J 0
(-6262 3958);
DISPLAY 0.489362 (-6262 3958);
PAINT GREEN (-6262 3958);
FORCEPROP 2 LAST CDS_LIB mstr_standard
J 0
(-6200 3950);
DISPLAY 0.723404 (-6200 3950);
PAINT MONO (-6200 3950);
DISPLAY INVISIBLE (-6200 3950);
FORCEPROP 1 LAST BODY_TYPE PLUMBING
J 0
(-6200 4000);
DISPLAY 0.872340 (-6200 4000);
PAINT GREEN (-6200 4000);
DISPLAY INVISIBLE (-6200 4000);
FORCEPROP 1 LAST HDL_TAP TRUE
J 0
(-5875 3825);
DISPLAY 0.872340 (-5875 3825);
DISPLAY INVISIBLE (-5875 3825);
FORCEPROP 1 LAST PATH I98
J 0
(-6202 3950);
DISPLAY 0.872340 (-6202 3950);
PAINT GREEN (-6202 3950);
DISPLAY INVISIBLE (-6202 3950);
FORCEADD TAP..1
(-6200 3900);
FORCEPROP 3 LASTPIN (-6250 3900) SIG_NAME M_C_CPU1_SA_DQ<1>
J 0
(-6240 3910);
DISPLAY 0.659574 (-6240 3910);
PAINT MONO (-6240 3910);
DISPLAY INVISIBLE (-6240 3910);
FORCEPROP 1 LASTPIN (-6250 3900) BN 1
J 0
(-6262 3908);
DISPLAY 0.489362 (-6262 3908);
PAINT GREEN (-6262 3908);
FORCEPROP 2 LAST CDS_LIB mstr_standard
J 0
(-6200 3900);
DISPLAY 0.723404 (-6200 3900);
PAINT MONO (-6200 3900);
DISPLAY INVISIBLE (-6200 3900);
FORCEPROP 1 LAST BODY_TYPE PLUMBING
J 0
(-6200 3950);
DISPLAY 0.872340 (-6200 3950);
PAINT GREEN (-6200 3950);
DISPLAY INVISIBLE (-6200 3950);
FORCEPROP 1 LAST HDL_TAP TRUE
J 0
(-5875 3775);
DISPLAY 0.872340 (-5875 3775);
DISPLAY INVISIBLE (-5875 3775);
FORCEPROP 1 LAST PATH I99
J 0
(-6202 3900);
DISPLAY 0.872340 (-6202 3900);
PAINT GREEN (-6202 3900);
DISPLAY INVISIBLE (-6202 3900);
FORCEADD QUANTA_TITLE_BLOCK_C..1
(-100 100);
FORCEPROP 0 LAST CDS_CON_LAST_MODIFIED Fri Mar 11 14:53:02 2022
J 0
(-1985 115);
DISPLAY INVISIBLE (-1985 115);
FORCEPROP 1 LAST CUSTOM_TXT_CDS <CON_LAST_MODIFIED>
J 0
(-1985 115);
DISPLAY 0.978723 (-1985 115);
FORCEPROP 2 LAST CUSTOM_TXT_CDS <XR_PAGE_TITLE>
J 0
(-7990 5350);
DISPLAY 0.638298 (-7990 5350);
PAINT PINK (-7990 5350);
DISPLAY INVISIBLE (-7990 5350);
FORCEPROP 1 LAST CUSTOM_TXT_CDS <NAME_2>
J 0
(-3275 150);
FORCEPROP 1 LAST CUSTOM_TXT_CDS <NAME_1>
J 0
(-3275 275);
FORCEPROP 1 LAST CUSTOM_TXT_CDS <Q_NUMBER>
J 0
(-1503 203);
DISPLAY 1.212766 (-1503 203);
FORCEPROP 1 LAST CUSTOM_TXT_CDS <Q_PROJ>
J 0
(-2482 202);
DISPLAY 1.212766 (-2482 202);
FORCEPROP 1 LAST CUSTOM_TXT_CDS <Q_REV>
J 0
(-284 203);
DISPLAY 1.212766 (-284 203);
FORCEPROP 1 LAST CUSTOM_TXT_CDS <CON_PAGE_NUM> OF <CON_TOTAL_PAGES>
J 0
(-546 118);
DISPLAY 0.978723 (-546 118);
FORCEPROP 1 LAST Q_TITLE DDR5 - CPU1 CHC
J 0
(-9425 125);
DISPLAY 2.446809 (-9425 125);
PAINT GREEN (-9425 125);
FORCEPROP 1 LAST Q_DEPT BU9
J 1
(-3863 149);
DISPLAY 1.957447 (-3863 149);
PAINT GREEN (-3863 149);
FORCEPROP 2 LAST PAGE_BORDER TRUE
J 0
(-7990 5350);
DISPLAY 0.638298 (-7990 5350);
PAINT PINK (-7990 5350);
DISPLAY INVISIBLE (-7990 5350);
FORCEPROP 2 LAST CDS_LIB pure_quanta
J 0
(-100 100);
DISPLAY INVISIBLE (-100 100);
FORCEPROP 1 LAST CDS_LMAN_SYM_OUTLINE -9475,6775,100,-125
J 0
(-100 100);
DISPLAY 0.468085 (-100 100);
PAINT GREEN (-100 100);
DISPLAY INVISIBLE (-100 100);
FORCEPROP 1 LAST COMMENT_BODY TRUE
J 0
(-88 87);
DISPLAY 0.978723 (-88 87);
PAINT GREEN (-88 87);
DISPLAY INVISIBLE (-88 87);
FORCEPROP 2 LAST CDS_XR_PAGE_TITLE CR-99 : @T6G_MB_LIB.T6G(SCH_1):PAGE99
J 0
(-7990 5350);
DISPLAY 0.638298 (-7990 5350);
PAINT PINK (-7990 5350);
DISPLAY INVISIBLE (-7990 5350);
FORCEADD DNS..2
(-8550 2300);
PAINT RED (-8550 2300);
FORCEPROP 2 LAST CDS_LIB mstr_misc
J 0
(-8550 2300);
DISPLAY INVISIBLE (-8550 2300);
FORCEPROP 1 LAST COMMENT_BODY TRUE
R 1
J 0
(-8475 2075);
DISPLAY 0.872340 (-8475 2075);
PAINT PEACH (-8475 2075);
DISPLAY INVISIBLE (-8475 2075);
WIRE 17 -1 (-6150 5425)(-6150 5375);
WIRE 17 -1 (-6150 5450)(-6150 5425);
WIRE 17 -1 (-6150 5375)(-6150 5325);
WIRE 17 -1 (-6150 5325)(-6150 5275);
WIRE 17 -1 (-6150 5450)(-5650 5450);
FORCEPROP 2 LAST SIG_NAME M_C_CPU1_SA_DQ<31:0>
J 2
(-5650 5460);
DISPLAY 0.489362 (-5650 5460);
WIRE 17 -1 (-7950 4025)(-7950 3975);
WIRE 17 -1 (-7950 4025)(-7950 4050);
WIRE 17 -1 (-7950 3925)(-7950 3975);
WIRE 17 -1 (-7950 3925)(-7950 3875);
WIRE 17 -1 (-7950 4050)(-8450 4050);
FORCEPROP 2 LAST SIG_NAME M_C_CPU1_SA_CB<7:0>
J 0
(-8450 4060);
DISPLAY 0.489362 (-8450 4060);
WIRE 17 -1 (-7950 3825)(-7950 3875);
WIRE 17 -1 (-7950 3775)(-7950 3825);
WIRE 17 -1 (-7950 3725)(-7950 3775);
WIRE 17 -1 (-7950 3675)(-7950 3725);
WIRE 17 -1 (-7950 3575)(-7950 3525);
WIRE 17 -1 (-7950 3575)(-7950 3600);
WIRE 17 -1 (-7950 3475)(-7950 3525);
WIRE 17 -1 (-7950 3475)(-7950 3425);
WIRE 17 -1 (-7950 3600)(-8450 3600);
FORCEPROP 2 LAST SIG_NAME M_C_CPU1_SB_CB<7:0>
J 0
(-8450 3610);
DISPLAY 0.489362 (-8450 3610);
WIRE 17 -1 (-7950 5125)(-7950 5175);
WIRE 17 -1 (-7950 5175)(-7950 5225);
WIRE 17 -1 (-7950 5225)(-7950 5275);
WIRE 17 -1 (-7950 5275)(-7950 5325);
WIRE 17 -1 (-7950 5325)(-7950 5375);
WIRE 17 -1 (-7950 5375)(-7950 5425);
WIRE 17 -1 (-7950 5425)(-7950 5450);
WIRE 17 -1 (-7950 5450)(-8450 5450);
FORCEPROP 2 LAST SIG_NAME M_C_CPU1_SA_CA<6:0>
J 0
(-8450 5460);
DISPLAY 0.489362 (-8450 5460);
WIRE 17 -1 (-7950 4725)(-7950 4775);
WIRE 17 -1 (-7950 4775)(-7950 4825);
WIRE 17 -1 (-7950 4825)(-7950 4875);
WIRE 17 -1 (-7950 4875)(-7950 4925);
WIRE 17 -1 (-7950 4925)(-7950 4975);
WIRE 17 -1 (-7950 4975)(-7950 5025);
WIRE 17 -1 (-7950 5025)(-7950 5050);
WIRE 17 -1 (-7950 5050)(-8450 5050);
FORCEPROP 2 LAST SIG_NAME M_C_CPU1_SB_CA<6:0>
J 0
(-8450 5060);
DISPLAY 0.489362 (-8450 5060);
WIRE 17 -1 (-7950 3375)(-7950 3425);
WIRE 17 -1 (-7950 3325)(-7950 3375);
WIRE 17 -1 (-7950 3275)(-7950 3325);
WIRE 17 -1 (-7950 3225)(-7950 3275);
WIRE 17 -1 (-6150 5275)(-6150 5225);
WIRE 17 -1 (-6150 5225)(-6150 5175);
WIRE 17 -1 (-6150 5175)(-6150 5125);
WIRE 17 -1 (-6150 5125)(-6150 5075);
WIRE 17 -1 (-6150 5075)(-6150 5025);
WIRE 17 -1 (-6150 5025)(-6150 4975);
WIRE 17 -1 (-6150 4975)(-6150 4925);
WIRE 17 -1 (-6150 4925)(-6150 4875);
WIRE 17 -1 (-6150 4875)(-6150 4825);
WIRE 17 -1 (-6150 4825)(-6150 4775);
WIRE 17 -1 (-6150 4775)(-6150 4725);
WIRE 17 -1 (-6150 4725)(-6150 4675);
WIRE 17 -1 (-6150 4625)(-6150 4675);
WIRE 17 -1 (-6150 4575)(-6150 4625);
WIRE 17 -1 (-6150 4525)(-6150 4575);
WIRE 17 -1 (-6150 4475)(-6150 4525);
WIRE 17 -1 (-6150 4475)(-6150 4425);
WIRE 17 -1 (-6150 4425)(-6150 4375);
WIRE 17 -1 (-6150 4375)(-6150 4325);
WIRE 17 -1 (-6150 4325)(-6150 4275);
WIRE 17 -1 (-6150 4275)(-6150 4225);
WIRE 17 -1 (-6150 4225)(-6150 4175);
WIRE 17 -1 (-6150 4175)(-6150 4125);
WIRE 17 -1 (-6150 4125)(-6150 4075);
WIRE 17 -1 (-6150 4025)(-6150 4075);
WIRE 17 -1 (-6150 3975)(-6150 4025);
WIRE 17 -1 (-6150 3925)(-6150 3975);
WIRE 17 -1 (-6150 3875)(-6150 3925);
WIRE 17 -1 (-6150 3775)(-6150 3725);
WIRE 17 -1 (-6150 3800)(-6150 3775);
WIRE 17 -1 (-6150 3725)(-6150 3675);
WIRE 17 -1 (-6150 3675)(-6150 3625);
WIRE 17 -1 (-6150 3800)(-5650 3800);
FORCEPROP 2 LAST SIG_NAME M_C_CPU1_SB_DQ<31:0>
J 2
(-5650 3810);
DISPLAY 0.489362 (-5650 3810);
WIRE 17 -1 (-6150 3625)(-6150 3575);
WIRE 17 -1 (-6150 3575)(-6150 3525);
WIRE 17 -1 (-6150 3525)(-6150 3475);
WIRE 17 -1 (-6150 3475)(-6150 3425);
WIRE 17 -1 (-6150 3425)(-6150 3375);
WIRE 17 -1 (-6150 3375)(-6150 3325);
WIRE 17 -1 (-6150 3325)(-6150 3275);
WIRE 17 -1 (-6150 3275)(-6150 3225);
WIRE 17 -1 (-6150 3225)(-6150 3175);
WIRE 17 -1 (-6150 3175)(-6150 3125);
WIRE 17 -1 (-6150 3125)(-6150 3075);
WIRE 17 -1 (-6150 3075)(-6150 3025);
WIRE 17 -1 (-6150 2975)(-6150 3025);
WIRE 17 -1 (-6150 2925)(-6150 2975);
WIRE 17 -1 (-6150 2875)(-6150 2925);
WIRE 17 -1 (-6150 2825)(-6150 2875);
WIRE 17 -1 (-6150 2825)(-6150 2775);
WIRE 17 -1 (-6150 2775)(-6150 2725);
WIRE 17 -1 (-6150 2725)(-6150 2675);
WIRE 17 -1 (-6150 2675)(-6150 2625);
WIRE 17 -1 (-6150 2625)(-6150 2575);
WIRE 17 -1 (-6150 2575)(-6150 2525);
WIRE 17 -1 (-6150 2525)(-6150 2475);
WIRE 17 -1 (-6150 2475)(-6150 2425);
WIRE 17 -1 (-6150 2375)(-6150 2425);
WIRE 17 -1 (-6150 2325)(-6150 2375);
WIRE 17 -1 (-6150 2275)(-6150 2325);
WIRE 17 -1 (-6150 2225)(-6150 2275);
WIRE 17 -1 (-3300 4325)(-3300 4225);
WIRE 17 -1 (-3300 4425)(-3300 4325);
WIRE 17 -1 (-3300 4225)(-3300 4125);
WIRE 17 -1 (-3300 4025)(-3300 4125);
WIRE 17 -1 (-3300 4525)(-3300 4425);
WIRE 17 -1 (-3300 4550)(-3300 4525);
WIRE 17 -1 (-3300 3925)(-3300 4025);
WIRE 17 -1 (-3300 3825)(-3300 3925);
WIRE 17 -1 (-3300 4550)(-2600 4550);
FORCEPROP 2 LAST SIG_NAME M_C_CPU1_SA_DQS_DN<9:0>
J 0
(-3235 4560);
DISPLAY 0.489362 (-3235 4560);
WIRE 17 -1 (-3500 4275)(-3500 4175);
WIRE 17 -1 (-3500 4375)(-3500 4275);
WIRE 17 -1 (-3500 4075)(-3500 4175);
WIRE 17 -1 (-3500 3975)(-3500 4075);
WIRE 17 -1 (-3500 4475)(-3500 4375);
WIRE 17 -1 (-3500 4575)(-3500 4475);
WIRE 17 -1 (-3500 3875)(-3500 3975);
WIRE 17 -1 (-3500 3875)(-3500 3775);
WIRE 17 -1 (-3500 4600)(-3500 4575);
WIRE 17 -1 (-3500 4600)(-2600 4600);
FORCEPROP 2 LAST SIG_NAME M_C_CPU1_SA_DQS_DP<9:0>
J 0
(-3235 4610);
DISPLAY 0.489362 (-3235 4610);
WIRE 17 -1 (-3500 3425)(-3500 3325);
WIRE 17 -1 (-3500 3525)(-3500 3425);
WIRE 17 -1 (-3500 3325)(-3500 3225);
WIRE 17 -1 (-3500 3225)(-3500 3125);
WIRE 17 -1 (-3500 3550)(-3500 3525);
WIRE 17 -1 (-3500 3550)(-2600 3550);
FORCEPROP 2 LAST SIG_NAME M_C_CPU1_SB_DQS_DP<9:0>
J 0
(-3235 3560);
DISPLAY 0.489362 (-3235 3560);
WIRE 17 -1 (-3300 3375)(-3300 3275);
WIRE 17 -1 (-3300 3475)(-3300 3375);
WIRE 17 -1 (-3300 3275)(-3300 3175);
WIRE 17 -1 (-3300 3175)(-3300 3075);
WIRE 17 -1 (-3300 3500)(-3300 3475);
WIRE 17 -1 (-3300 3500)(-2600 3500);
FORCEPROP 2 LAST SIG_NAME M_C_CPU1_SB_DQS_DN<9:0>
J 0
(-3235 3510);
DISPLAY 0.489362 (-3235 3510);
WIRE 17 -1 (-3500 3025)(-3500 3125);
WIRE 17 -1 (-3500 2925)(-3500 3025);
WIRE 17 -1 (-3500 2825)(-3500 2925);
WIRE 17 -1 (-3300 3725)(-3300 3625);
WIRE 17 -1 (-3300 3825)(-3300 3725);
WIRE 17 -1 (-3500 3775)(-3500 3675);
WIRE 17 -1 (-3300 2675)(-3300 2575);
WIRE 17 -1 (-3300 2775)(-3300 2675);
WIRE 17 -1 (-3300 2775)(-3300 2875);
WIRE 17 -1 (-3300 2875)(-3300 2975);
WIRE 17 -1 (-3300 2975)(-3300 3075);
WIRE 17 -1 (-3500 2725)(-3500 2625);
WIRE 17 -1 (-3500 2825)(-3500 2725);
WIRE 16 -1 (-6600 1075)(-6600 1150);
WIRE 16 -1 (-8775 3050)(-8775 3125);
WIRE 16 -1 (-8575 2400)(-8575 2425);
WIRE 16 -1 (-8050 2700)(-8475 2700);
FORCEPROP 2 LAST SIG_NAME I3C_SPD_DDRAF_CPU1_SCL
J 0
(-8535 2710);
DISPLAY 0.489362 (-8535 2710);
WIRE 16 -1 (-7750 2700)(-7850 2700);
WIRE 16 -1 (-7750 2800)(-7750 2700);
WIRE 16 -1 (-7650 2800)(-7750 2800);
FORCEPROP 2 LAST SIG_NAME I3C_SPD_DDRC_CPU1_SCL
J 0
(-8135 2810);
DISPLAY 0.446809 (-8135 2810);
FORCEPROP 2 LASTPROP $XRERR UNIQUE?
J 0
(-8375 2810);
DISPLAY 0.638298 (-8375 2810);
PAINT MONO (-8375 2810);
DISPLAY INVISIBLE (-8375 2810);
WIRE 16 -1 (-8375 2150)(-8575 2150);
WIRE 16 -1 (-8375 2150)(-8375 2550);
WIRE 16 -1 (-8575 2200)(-8575 2150);
WIRE 16 -1 (-8575 2150)(-8600 2150);
WIRE 16 -1 (-7650 2550)(-8375 2550);
FORCEPROP 2 LAST SIG_NAME PWRGD_CHC_CPU1_DIMM
J 0
(-8275 2560);
DISPLAY 0.489362 (-8275 2560);
FORCEPROP 2 LASTPROP $XRERR UNIQUE?
J 0
(-8515 2560);
DISPLAY 0.638298 (-8515 2560);
PAINT MONO (-8515 2560);
DISPLAY INVISIBLE (-8515 2560);
WIRE 16 -1 (-7650 2850)(-8450 2850);
FORCEPROP 2 LAST SIG_NAME I3C_SPD_DDRAF_CPU1_SDA
J 0
(-8460 2860);
DISPLAY 0.489362 (-8460 2860);
WIRE 16 -1 (-7650 2350)(-8275 2350);
FORCEPROP 2 LAST SIG_NAME TP_CHC_CPU1_DIMM_RFU_4
J 0
(-8275 2360);
DISPLAY 0.489362 (-8275 2360);
FORCEPROP 2 LASTPROP $XRERR UNIQUE?
J 0
(-8515 2350);
DISPLAY 0.638298 (-8515 2350);
PAINT MONO (-8515 2350);
DISPLAY INVISIBLE (-8515 2350);
WIRE 16 -1 (-7650 2400)(-8275 2400);
FORCEPROP 2 LAST SIG_NAME TP_CHC_CPU1_DIMM_RFU_5
J 0
(-8275 2410);
DISPLAY 0.489362 (-8275 2410);
FORCEPROP 2 LASTPROP $XRERR UNIQUE?
J 0
(-8515 2400);
DISPLAY 0.638298 (-8515 2400);
PAINT MONO (-8515 2400);
DISPLAY INVISIBLE (-8515 2400);
WIRE 16 -1 (-7650 2450)(-8275 2450);
FORCEPROP 2 LAST SIG_NAME TP_CHC_CPU1_DIMM_RFU_6
J 0
(-8275 2460);
DISPLAY 0.489362 (-8275 2460);
FORCEPROP 2 LASTPROP $XRERR UNIQUE?
J 0
(-8515 2450);
DISPLAY 0.638298 (-8515 2450);
PAINT MONO (-8515 2450);
DISPLAY INVISIBLE (-8515 2450);
WIRE 16 -1 (-7650 2900)(-8450 2900);
FORCEPROP 2 LAST SIG_NAME PD_CHC_CPU1_DIMM_SAA
J 0
(-8450 2910);
DISPLAY 0.489362 (-8450 2910);
WIRE 16 -1 (-8675 2950)(-7650 2950);
WIRE 16 -1 (-8675 3350)(-8675 2950);
WIRE 16 -1 (-8675 3375)(-8675 3350);
WIRE 16 -1 (-8775 3350)(-8675 3350);
WIRE 16 -1 (-8775 3325)(-8775 3350);
WIRE 16 -1 (-9150 2150)(-8800 2150);
FORCEPROP 2 LAST SIG_NAME PWRGD_CHAF_CPU1
J 0
(-9160 2160);
DISPLAY 0.489362 (-9160 2160);
WIRE 16 -1 (-1925 5300)(-2225 5300);
WIRE 16 -1 (-2225 5300)(-2225 5350);
WIRE 16 -1 (-1925 5350)(-2225 5350);
WIRE 16 -1 (-2225 5350)(-2225 5400);
WIRE 16 -1 (-1925 5400)(-2225 5400);
WIRE 16 -1 (-2225 5400)(-2225 6075);
WIRE 16 -1 (-2350 6075)(-2225 6075);
WIRE 16 -1 (-2350 6075)(-2925 6075);
WIRE 16 -1 (-2350 6075)(-2350 5975);
WIRE 16 -1 (-2925 6075)(-2925 6150);
WIRE 16 -1 (-2925 5975)(-2925 6075);
WIRE 16 -1 (-2350 5650)(-2925 5650);
WIRE 16 -1 (-2350 5650)(-2350 5775);
WIRE 16 -1 (-2925 5650)(-2925 5775);
WIRE 16 -1 (-2925 5650)(-2925 5575);
WIRE 16 -1 (-425 5400)(-425 5350);
WIRE 16 -1 (-425 5400)(-725 5400);
WIRE 16 -1 (-425 5350)(-425 5300);
WIRE 16 -1 (-425 5350)(-725 5350);
WIRE 16 -1 (-425 5300)(-425 5250);
WIRE 16 -1 (-425 5300)(-725 5300);
WIRE 16 -1 (-425 5250)(-425 5200);
WIRE 16 -1 (-425 5250)(-725 5250);
WIRE 16 -1 (-425 5200)(-425 5150);
WIRE 16 -1 (-425 5200)(-725 5200);
WIRE 16 -1 (-425 5150)(-725 5150);
WIRE 16 -1 (-425 5150)(-425 5100);
WIRE 16 -1 (-425 5100)(-425 5050);
WIRE 16 -1 (-425 5100)(-725 5100);
WIRE 16 -1 (-425 5050)(-425 5000);
WIRE 16 -1 (-425 5050)(-725 5050);
WIRE 16 -1 (-425 5000)(-425 4950);
WIRE 16 -1 (-425 5000)(-725 5000);
WIRE 16 -1 (-425 4950)(-425 4900);
WIRE 16 -1 (-425 4950)(-725 4950);
WIRE 16 -1 (-425 4900)(-425 4850);
WIRE 16 -1 (-425 4900)(-725 4900);
WIRE 16 -1 (-425 4850)(-425 4800);
WIRE 16 -1 (-425 4850)(-725 4850);
WIRE 16 -1 (-425 4800)(-425 4750);
WIRE 16 -1 (-425 4800)(-725 4800);
WIRE 16 -1 (-425 4750)(-425 4700);
WIRE 16 -1 (-425 4750)(-725 4750);
WIRE 16 -1 (-425 4700)(-425 4650);
WIRE 16 -1 (-425 4700)(-725 4700);
WIRE 16 -1 (-425 4650)(-425 4600);
WIRE 16 -1 (-425 4650)(-725 4650);
WIRE 16 -1 (-425 4600)(-425 4550);
WIRE 16 -1 (-425 4600)(-725 4600);
WIRE 16 -1 (-425 4550)(-425 4500);
WIRE 16 -1 (-425 4550)(-725 4550);
WIRE 16 -1 (-425 4500)(-425 4450);
WIRE 16 -1 (-425 4500)(-725 4500);
WIRE 16 -1 (-425 4450)(-425 4400);
WIRE 16 -1 (-425 4450)(-725 4450);
WIRE 16 -1 (-425 4400)(-425 4350);
WIRE 16 -1 (-425 4400)(-725 4400);
WIRE 16 -1 (-425 4350)(-425 4300);
WIRE 16 -1 (-425 4350)(-725 4350);
WIRE 16 -1 (-425 4300)(-425 4250);
WIRE 16 -1 (-425 4300)(-725 4300);
WIRE 16 -1 (-425 4250)(-425 4200);
WIRE 16 -1 (-425 4250)(-725 4250);
WIRE 16 -1 (-425 4200)(-425 4150);
WIRE 16 -1 (-425 4200)(-725 4200);
WIRE 16 -1 (-425 4150)(-425 4100);
WIRE 16 -1 (-425 4150)(-725 4150);
WIRE 16 -1 (-425 4100)(-725 4100);
WIRE 16 -1 (-425 4100)(-425 4050);
WIRE 16 -1 (-425 4050)(-425 4000);
WIRE 16 -1 (-425 4050)(-725 4050);
WIRE 16 -1 (-425 4000)(-425 3950);
WIRE 16 -1 (-425 4000)(-725 4000);
WIRE 16 -1 (-425 3950)(-425 3900);
WIRE 16 -1 (-425 3950)(-725 3950);
WIRE 16 -1 (-425 3900)(-425 3850);
WIRE 16 -1 (-425 3900)(-725 3900);
WIRE 16 -1 (-425 3850)(-425 3800);
WIRE 16 -1 (-425 3850)(-725 3850);
WIRE 16 -1 (-425 3800)(-425 3750);
WIRE 16 -1 (-425 3800)(-725 3800);
WIRE 16 -1 (-425 3750)(-425 3700);
WIRE 16 -1 (-425 3750)(-725 3750);
WIRE 16 -1 (-425 3700)(-425 3650);
WIRE 16 -1 (-425 3700)(-725 3700);
WIRE 16 -1 (-425 3650)(-425 3600);
WIRE 16 -1 (-425 3650)(-725 3650);
WIRE 16 -1 (-425 3600)(-425 3550);
WIRE 16 -1 (-425 3600)(-725 3600);
WIRE 16 -1 (-425 3550)(-425 3500);
WIRE 16 -1 (-425 3550)(-725 3550);
WIRE 16 -1 (-425 3500)(-425 3450);
WIRE 16 -1 (-425 3500)(-725 3500);
WIRE 16 -1 (-425 3450)(-425 3400);
WIRE 16 -1 (-425 3450)(-725 3450);
WIRE 16 -1 (-425 3400)(-425 3350);
WIRE 16 -1 (-425 3400)(-725 3400);
WIRE 16 -1 (-425 3350)(-425 3300);
WIRE 16 -1 (-425 3350)(-725 3350);
WIRE 16 -1 (-425 3300)(-425 3250);
WIRE 16 -1 (-425 3300)(-725 3300);
WIRE 16 -1 (-425 3250)(-425 3200);
WIRE 16 -1 (-425 3250)(-725 3250);
WIRE 16 -1 (-425 3200)(-425 3150);
WIRE 16 -1 (-425 3200)(-725 3200);
WIRE 16 -1 (-425 3150)(-425 3100);
WIRE 16 -1 (-425 3150)(-725 3150);
WIRE 16 -1 (-425 3100)(-725 3100);
WIRE 16 -1 (-425 3100)(-425 3050);
WIRE 16 -1 (-425 3050)(-425 3000);
WIRE 16 -1 (-425 3050)(-725 3050);
WIRE 16 -1 (-425 3000)(-425 2950);
WIRE 16 -1 (-425 3000)(-725 3000);
WIRE 16 -1 (-425 2950)(-425 2900);
WIRE 16 -1 (-425 2950)(-725 2950);
WIRE 16 -1 (-425 2900)(-425 2850);
WIRE 16 -1 (-425 2900)(-725 2900);
WIRE 16 -1 (-425 2850)(-425 2800);
WIRE 16 -1 (-425 2850)(-725 2850);
WIRE 16 -1 (-425 2800)(-425 2750);
WIRE 16 -1 (-425 2800)(-725 2800);
WIRE 16 -1 (-425 2750)(-425 2700);
WIRE 16 -1 (-425 2750)(-725 2750);
WIRE 16 -1 (-425 2700)(-425 2650);
WIRE 16 -1 (-425 2700)(-725 2700);
WIRE 16 -1 (-425 2650)(-425 2600);
WIRE 16 -1 (-425 2650)(-725 2650);
WIRE 16 -1 (-425 2600)(-425 2550);
WIRE 16 -1 (-425 2600)(-725 2600);
WIRE 16 -1 (-425 2550)(-425 2500);
WIRE 16 -1 (-425 2550)(-725 2550);
WIRE 16 -1 (-425 2500)(-425 2450);
WIRE 16 -1 (-425 2500)(-725 2500);
WIRE 16 -1 (-425 2450)(-425 2400);
WIRE 16 -1 (-425 2450)(-725 2450);
WIRE 16 -1 (-425 2400)(-425 2350);
WIRE 16 -1 (-425 2400)(-725 2400);
WIRE 16 -1 (-425 2350)(-425 2300);
WIRE 16 -1 (-425 2350)(-725 2350);
WIRE 16 -1 (-425 2300)(-425 2250);
WIRE 16 -1 (-425 2300)(-725 2300);
WIRE 16 -1 (-425 2250)(-425 2150);
WIRE 16 -1 (-425 2250)(-725 2250);
WIRE 16 -1 (-425 2150)(-425 2100);
WIRE 16 -1 (-425 2150)(-725 2150);
WIRE 16 -1 (-425 2100)(-425 2050);
WIRE 16 -1 (-425 2100)(-725 2100);
WIRE 16 -1 (-425 2050)(-725 2050);
WIRE 16 -1 (-425 2050)(-425 1850);
WIRE 16 -1 (-1925 2150)(-2225 2150);
WIRE 16 -1 (-2225 2200)(-2225 2150);
WIRE 16 -1 (-2225 2150)(-2225 2050);
WIRE 16 -1 (-1925 2200)(-2225 2200);
WIRE 16 -1 (-2225 2250)(-2225 2200);
WIRE 16 -1 (-1925 2250)(-2225 2250);
WIRE 16 -1 (-2225 2300)(-2225 2250);
WIRE 16 -1 (-1925 2300)(-2225 2300);
WIRE 16 -1 (-2225 2350)(-2225 2300);
WIRE 16 -1 (-1925 2350)(-2225 2350);
WIRE 16 -1 (-2225 2400)(-2225 2350);
WIRE 16 -1 (-1925 2400)(-2225 2400);
WIRE 16 -1 (-2225 2450)(-2225 2400);
WIRE 16 -1 (-1925 2450)(-2225 2450);
WIRE 16 -1 (-2225 2500)(-2225 2450);
WIRE 16 -1 (-1925 2500)(-2225 2500);
WIRE 16 -1 (-2225 2550)(-2225 2500);
WIRE 16 -1 (-1925 2550)(-2225 2550);
WIRE 16 -1 (-2225 2600)(-2225 2550);
WIRE 16 -1 (-1925 2600)(-2225 2600);
WIRE 16 -1 (-2225 2650)(-2225 2600);
WIRE 16 -1 (-1925 2650)(-2225 2650);
WIRE 16 -1 (-2225 2700)(-2225 2650);
WIRE 16 -1 (-1925 2700)(-2225 2700);
WIRE 16 -1 (-2225 2750)(-2225 2700);
WIRE 16 -1 (-1925 2750)(-2225 2750);
WIRE 16 -1 (-2225 2800)(-2225 2750);
WIRE 16 -1 (-1925 2800)(-2225 2800);
WIRE 16 -1 (-2225 2850)(-2225 2800);
WIRE 16 -1 (-1925 2850)(-2225 2850);
WIRE 16 -1 (-2225 2900)(-2225 2850);
WIRE 16 -1 (-1925 2900)(-2225 2900);
WIRE 16 -1 (-2225 2950)(-2225 2900);
WIRE 16 -1 (-1925 2950)(-2225 2950);
WIRE 16 -1 (-2225 3000)(-2225 2950);
WIRE 16 -1 (-1925 3000)(-2225 3000);
WIRE 16 -1 (-2225 3050)(-2225 3000);
WIRE 16 -1 (-1925 3050)(-2225 3050);
WIRE 16 -1 (-2225 3100)(-2225 3050);
WIRE 16 -1 (-1925 3100)(-2225 3100);
WIRE 16 -1 (-2225 3150)(-2225 3100);
WIRE 16 -1 (-1925 3150)(-2225 3150);
WIRE 16 -1 (-2225 3200)(-2225 3150);
WIRE 16 -1 (-1925 3200)(-2225 3200);
WIRE 16 -1 (-2225 3250)(-2225 3200);
WIRE 16 -1 (-1925 3250)(-2225 3250);
WIRE 16 -1 (-2225 3300)(-2225 3250);
WIRE 16 -1 (-1925 3300)(-2225 3300);
WIRE 16 -1 (-2225 3350)(-2225 3300);
WIRE 16 -1 (-1925 3350)(-2225 3350);
WIRE 16 -1 (-2225 3400)(-2225 3350);
WIRE 16 -1 (-1925 3400)(-2225 3400);
WIRE 16 -1 (-2225 3450)(-2225 3400);
WIRE 16 -1 (-1925 3450)(-2225 3450);
WIRE 16 -1 (-2225 3500)(-2225 3450);
WIRE 16 -1 (-1925 3500)(-2225 3500);
WIRE 16 -1 (-2225 3550)(-2225 3500);
WIRE 16 -1 (-1925 3550)(-2225 3550);
WIRE 16 -1 (-2225 3600)(-2225 3550);
WIRE 16 -1 (-1925 3600)(-2225 3600);
WIRE 16 -1 (-2225 3650)(-2225 3600);
WIRE 16 -1 (-1925 3650)(-2225 3650);
WIRE 16 -1 (-2225 3700)(-2225 3650);
WIRE 16 -1 (-1925 3700)(-2225 3700);
WIRE 16 -1 (-2225 3750)(-2225 3700);
WIRE 16 -1 (-1925 3750)(-2225 3750);
WIRE 16 -1 (-2225 3800)(-2225 3750);
WIRE 16 -1 (-1925 3800)(-2225 3800);
WIRE 16 -1 (-2225 3850)(-2225 3800);
WIRE 16 -1 (-1925 3850)(-2225 3850);
WIRE 16 -1 (-2225 3900)(-2225 3850);
WIRE 16 -1 (-1925 3900)(-2225 3900);
WIRE 16 -1 (-2225 3950)(-2225 3900);
WIRE 16 -1 (-1925 3950)(-2225 3950);
WIRE 16 -1 (-2225 4000)(-2225 3950);
WIRE 16 -1 (-1925 4000)(-2225 4000);
WIRE 16 -1 (-2225 4050)(-2225 4000);
WIRE 16 -1 (-2225 4100)(-2225 4050);
WIRE 16 -1 (-1925 4050)(-2225 4050);
WIRE 16 -1 (-1925 4100)(-2225 4100);
WIRE 16 -1 (-2225 4150)(-2225 4100);
WIRE 16 -1 (-1925 4150)(-2225 4150);
WIRE 16 -1 (-2225 4200)(-2225 4150);
WIRE 16 -1 (-1925 4200)(-2225 4200);
WIRE 16 -1 (-2225 4250)(-2225 4200);
WIRE 16 -1 (-1925 4250)(-2225 4250);
WIRE 16 -1 (-2225 4300)(-2225 4250);
WIRE 16 -1 (-1925 4300)(-2225 4300);
WIRE 16 -1 (-2225 4350)(-2225 4300);
WIRE 16 -1 (-1925 4350)(-2225 4350);
WIRE 16 -1 (-2225 4400)(-2225 4350);
WIRE 16 -1 (-1925 4400)(-2225 4400);
WIRE 16 -1 (-2225 4450)(-2225 4400);
WIRE 16 -1 (-1925 4450)(-2225 4450);
WIRE 16 -1 (-2225 4500)(-2225 4450);
WIRE 16 -1 (-1925 4500)(-2225 4500);
WIRE 16 -1 (-2225 4550)(-2225 4500);
WIRE 16 -1 (-1925 4550)(-2225 4550);
WIRE 16 -1 (-2225 4600)(-2225 4550);
WIRE 16 -1 (-1925 4600)(-2225 4600);
WIRE 16 -1 (-2225 4650)(-2225 4600);
WIRE 16 -1 (-1925 4650)(-2225 4650);
WIRE 16 -1 (-2225 4700)(-2225 4650);
WIRE 16 -1 (-1925 4700)(-2225 4700);
WIRE 16 -1 (-2225 4750)(-2225 4700);
WIRE 16 -1 (-1925 4750)(-2225 4750);
WIRE 16 -1 (-2225 4800)(-2225 4750);
WIRE 16 -1 (-1925 4800)(-2225 4800);
WIRE 16 -1 (-2225 4850)(-2225 4800);
WIRE 16 -1 (-1925 4850)(-2225 4850);
WIRE 16 -1 (-2225 4900)(-2225 4850);
WIRE 16 -1 (-1925 4900)(-2225 4900);
WIRE 16 -1 (-2225 4950)(-2225 4900);
WIRE 16 -1 (-1925 4950)(-2225 4950);
WIRE 16 -1 (-2225 5000)(-2225 4950);
WIRE 16 -1 (-1925 5000)(-2225 5000);
WIRE 16 -1 (-2225 5050)(-2225 5000);
WIRE 16 -1 (-1925 5050)(-2225 5050);
WIRE 16 -1 (-2225 5100)(-2225 5050);
WIRE 16 -1 (-1925 5100)(-2225 5100);
WIRE 16 -1 (-2225 5150)(-2225 5100);
WIRE 16 -1 (-1925 5150)(-2225 5150);
WIRE 16 -1 (-2225 5200)(-2225 5150);
WIRE 16 -1 (-1925 5200)(-2225 5200);
WIRE 16 -1 (-2225 5250)(-2225 5200);
WIRE 16 -1 (-1925 5250)(-2225 5250);
WIRE 16 -1 (-3750 3500)(-3600 3500);
WIRE 16 -1 (-3750 3450)(-3400 3450);
WIRE 16 -1 (-3750 4550)(-3600 4550);
WIRE 16 -1 (-3750 4500)(-3400 4500);
WIRE 16 -1 (-3600 4450)(-3750 4450);
WIRE 16 -1 (-3750 4400)(-3400 4400);
WIRE 16 -1 (-3750 3250)(-3400 3250);
WIRE 16 -1 (-3600 4350)(-3750 4350);
WIRE 16 -1 (-3600 3200)(-3750 3200);
WIRE 16 -1 (-3750 3150)(-3400 3150);
WIRE 16 -1 (-3750 4200)(-3400 4200);
WIRE 16 -1 (-3750 3100)(-3600 3100);
WIRE 16 -1 (-3750 3050)(-3400 3050);
WIRE 16 -1 (-3750 4150)(-3600 4150);
WIRE 16 -1 (-3400 4100)(-3750 4100);
WIRE 16 -1 (-3600 3000)(-3750 3000);
WIRE 16 -1 (-3750 2950)(-3400 2950);
WIRE 16 -1 (-3600 4050)(-3750 4050);
WIRE 16 -1 (-3750 4000)(-3400 4000);
WIRE 16 -1 (-3600 2900)(-3750 2900);
WIRE 16 -1 (-3750 2850)(-3400 2850);
WIRE 16 -1 (-3600 3950)(-3750 3950);
WIRE 16 -1 (-3400 3900)(-3750 3900);
WIRE 16 -1 (-3600 2800)(-3750 2800);
WIRE 16 -1 (-3750 2750)(-3400 2750);
WIRE 16 -1 (-3600 3850)(-3750 3850);
WIRE 16 -1 (-3750 3800)(-3400 3800);
WIRE 16 -1 (-3750 2700)(-3600 2700);
WIRE 16 -1 (-3750 2650)(-3400 2650);
WIRE 16 -1 (-3750 3750)(-3600 3750);
WIRE 16 -1 (-3750 3700)(-3400 3700);
WIRE 16 -1 (-3600 2600)(-3750 2600);
WIRE 16 -1 (-3750 2550)(-3400 2550);
WIRE 16 -1 (-3600 3650)(-3750 3650);
WIRE 16 -1 (-3750 3600)(-3400 3600);
WIRE 16 -1 (-3600 3300)(-3750 3300);
WIRE 16 -1 (-3750 3350)(-3400 3350);
WIRE 16 -1 (-3600 3400)(-3750 3400);
WIRE 16 -1 (-3600 4250)(-3750 4250);
WIRE 16 -1 (-3750 4300)(-3400 4300);
WIRE 16 -1 (-7650 2150)(-8275 2150);
FORCEPROP 2 LAST SIG_NAME TP_CHC_CPU1_DIMM_RFU_0
J 0
(-8275 2160);
DISPLAY 0.489362 (-8275 2160);
FORCEPROP 2 LASTPROP $XRERR UNIQUE?
J 0
(-8515 2150);
DISPLAY 0.638298 (-8515 2150);
PAINT MONO (-8515 2150);
DISPLAY INVISIBLE (-8515 2150);
WIRE 16 -1 (-7650 2200)(-8275 2200);
FORCEPROP 2 LAST SIG_NAME TP_CHC_CPU1_DIMM_RFU_1
J 0
(-8275 2210);
DISPLAY 0.489362 (-8275 2210);
FORCEPROP 2 LASTPROP $XRERR UNIQUE?
J 0
(-8515 2200);
DISPLAY 0.638298 (-8515 2200);
PAINT MONO (-8515 2200);
DISPLAY INVISIBLE (-8515 2200);
WIRE 16 -1 (-7650 2250)(-8275 2250);
FORCEPROP 2 LAST SIG_NAME TP_CHC_CPU1_DIMM_RFU_2
J 0
(-8275 2260);
DISPLAY 0.489362 (-8275 2260);
FORCEPROP 2 LASTPROP $XRERR UNIQUE?
J 0
(-8515 2250);
DISPLAY 0.638298 (-8515 2250);
PAINT MONO (-8515 2250);
DISPLAY INVISIBLE (-8515 2250);
WIRE 16 -1 (-7650 2300)(-8275 2300);
FORCEPROP 2 LAST SIG_NAME TP_CHC_CPU1_DIMM_RFU_3
J 0
(-8275 2310);
DISPLAY 0.489362 (-8275 2310);
FORCEPROP 2 LASTPROP $XRERR UNIQUE?
J 0
(-8515 2300);
DISPLAY 0.638298 (-8515 2300);
PAINT MONO (-8515 2300);
DISPLAY INVISIBLE (-8515 2300);
WIRE 16 -1 (-7650 3100)(-8275 3100);
FORCEPROP 2 LAST SIG_NAME M_C_CPU1_RESET_N
J 0
(-8275 3110);
DISPLAY 0.489362 (-8275 3110);
WIRE 16 -1 (-7650 4550)(-8450 4550);
FORCEPROP 2 LAST SIG_NAME M_C_CPU1_SB_PAR
J 0
(-8450 4560);
DISPLAY 0.489362 (-8450 4560);
WIRE 16 -1 (-7650 4600)(-8450 4600);
FORCEPROP 2 LAST SIG_NAME M_C_CPU1_SA_PAR
J 0
(-8450 4610);
DISPLAY 0.489362 (-8450 4610);
WIRE 16 -1 (-7650 1950)(-8450 1950);
FORCEPROP 2 LAST SIG_NAME M_C_CPU1_SB_RSP<0>
J 0
(-8450 1960);
DISPLAY 0.489362 (-8450 1960);
WIRE 16 -1 (-7650 2000)(-8450 2000);
FORCEPROP 2 LAST SIG_NAME M_C_CPU1_SA_RSP<0>
J 0
(-8450 2010);
DISPLAY 0.489362 (-8450 2010);
WIRE 16 -1 (-6250 2200)(-6450 2200);
WIRE 16 -1 (-6250 2250)(-6450 2250);
WIRE 16 -1 (-6250 2300)(-6450 2300);
WIRE 16 -1 (-6450 2350)(-6250 2350);
WIRE 16 -1 (-6250 2400)(-6450 2400);
WIRE 16 -1 (-6250 2450)(-6450 2450);
WIRE 16 -1 (-6250 2500)(-6450 2500);
WIRE 16 -1 (-6450 2550)(-6250 2550);
WIRE 16 -1 (-6250 2600)(-6450 2600);
WIRE 16 -1 (-6250 2650)(-6450 2650);
WIRE 16 -1 (-6250 2700)(-6450 2700);
WIRE 16 -1 (-6450 2750)(-6250 2750);
WIRE 16 -1 (-6250 2800)(-6450 2800);
WIRE 16 -1 (-6250 2850)(-6450 2850);
WIRE 16 -1 (-6250 2900)(-6450 2900);
WIRE 16 -1 (-6450 2950)(-6250 2950);
WIRE 16 -1 (-6250 3000)(-6450 3000);
WIRE 16 -1 (-6250 3050)(-6450 3050);
WIRE 16 -1 (-6250 3100)(-6450 3100);
WIRE 16 -1 (-6450 3150)(-6250 3150);
WIRE 16 -1 (-6250 3200)(-6450 3200);
WIRE 16 -1 (-6250 3250)(-6450 3250);
WIRE 16 -1 (-6250 3300)(-6450 3300);
WIRE 16 -1 (-6450 3350)(-6250 3350);
WIRE 16 -1 (-6250 3400)(-6450 3400);
WIRE 16 -1 (-6250 3450)(-6450 3450);
WIRE 16 -1 (-6250 3500)(-6450 3500);
WIRE 16 -1 (-6450 3550)(-6250 3550);
WIRE 16 -1 (-6250 3600)(-6450 3600);
WIRE 16 -1 (-6250 3650)(-6450 3650);
WIRE 16 -1 (-6250 3700)(-6450 3700);
WIRE 16 -1 (-6450 3750)(-6250 3750);
WIRE 16 -1 (-6250 3850)(-6450 3850);
WIRE 16 -1 (-6250 3900)(-6450 3900);
WIRE 16 -1 (-6250 3950)(-6450 3950);
WIRE 16 -1 (-6450 4000)(-6250 4000);
WIRE 16 -1 (-6250 4050)(-6450 4050);
WIRE 16 -1 (-6250 4100)(-6450 4100);
WIRE 16 -1 (-6250 4150)(-6450 4150);
WIRE 16 -1 (-6450 4200)(-6250 4200);
WIRE 16 -1 (-6250 4250)(-6450 4250);
WIRE 16 -1 (-6250 4300)(-6450 4300);
WIRE 16 -1 (-6250 4350)(-6450 4350);
WIRE 16 -1 (-6450 4400)(-6250 4400);
WIRE 16 -1 (-6250 4450)(-6450 4450);
WIRE 16 -1 (-6250 4500)(-6450 4500);
WIRE 16 -1 (-6250 4550)(-6450 4550);
WIRE 16 -1 (-6450 4600)(-6250 4600);
WIRE 16 -1 (-6250 4650)(-6450 4650);
WIRE 16 -1 (-6250 4700)(-6450 4700);
WIRE 16 -1 (-6250 4750)(-6450 4750);
WIRE 16 -1 (-6450 4800)(-6250 4800);
WIRE 16 -1 (-6250 4850)(-6450 4850);
WIRE 16 -1 (-6250 4900)(-6450 4900);
WIRE 16 -1 (-6250 4950)(-6450 4950);
WIRE 16 -1 (-6450 5000)(-6250 5000);
WIRE 16 -1 (-6250 5050)(-6450 5050);
WIRE 16 -1 (-6250 5100)(-6450 5100);
WIRE 16 -1 (-6250 5150)(-6450 5150);
WIRE 16 -1 (-6450 5200)(-6250 5200);
WIRE 16 -1 (-6250 5250)(-6450 5250);
WIRE 16 -1 (-6250 5300)(-6450 5300);
WIRE 16 -1 (-6250 5350)(-6450 5350);
WIRE 16 -1 (-7650 4300)(-8450 4300);
FORCEPROP 2 LAST SIG_NAME M_C_CPU1_SB_CS_N<1>
J 0
(-8450 4310);
DISPLAY 0.489362 (-8450 4310);
WIRE 16 -1 (-7650 4450)(-8450 4450);
FORCEPROP 2 LAST SIG_NAME M_C_CPU1_SA_CS_N<1>
J 0
(-8450 4460);
DISPLAY 0.489362 (-8450 4460);
WIRE 16 -1 (-7650 4250)(-8450 4250);
FORCEPROP 2 LAST SIG_NAME M_C_CPU1_SB_CS_N<0>
J 0
(-8450 4260);
DISPLAY 0.489362 (-8450 4260);
WIRE 16 -1 (-7650 4400)(-8450 4400);
FORCEPROP 2 LAST SIG_NAME M_C_CPU1_SA_CS_N<0>
J 0
(-8450 4410);
DISPLAY 0.489362 (-8450 4410);
WIRE 16 -1 (-7650 4150)(-8450 4150);
FORCEPROP 2 LAST SIG_NAME M_C_CPU1_CLK_DP<0>
J 0
(-8450 4160);
DISPLAY 0.489362 (-8450 4160);
WIRE 16 -1 (-7650 4100)(-8450 4100);
FORCEPROP 2 LAST SIG_NAME M_C_CPU1_CLK_DN<0>
J 0
(-8450 4110);
DISPLAY 0.489362 (-8450 4110);
WIRE 16 -1 (-7650 3200)(-7850 3200);
WIRE 16 -1 (-7650 3250)(-7850 3250);
WIRE 16 -1 (-7650 3300)(-7850 3300);
WIRE 16 -1 (-7650 3350)(-7850 3350);
WIRE 16 -1 (-7650 3400)(-7850 3400);
WIRE 16 -1 (-7650 3450)(-7850 3450);
WIRE 16 -1 (-7650 3500)(-7850 3500);
WIRE 16 -1 (-7650 3650)(-7850 3650);
WIRE 16 -1 (-7650 3750)(-7850 3750);
WIRE 16 -1 (-7650 3800)(-7850 3800);
WIRE 16 -1 (-7650 3900)(-7850 3900);
WIRE 16 -1 (-7650 3950)(-7850 3950);
WIRE 16 -1 (-7650 5000)(-7850 5000);
WIRE 16 -1 (-7650 5400)(-7850 5400);
WIRE 16 -1 (-7650 4950)(-7850 4950);
WIRE 16 -1 (-7650 5350)(-7850 5350);
WIRE 16 -1 (-7650 4900)(-7850 4900);
WIRE 16 -1 (-7650 5300)(-7850 5300);
WIRE 16 -1 (-7650 4850)(-7850 4850);
WIRE 16 -1 (-7650 5250)(-7850 5250);
WIRE 16 -1 (-7650 4800)(-7850 4800);
WIRE 16 -1 (-7650 5200)(-7850 5200);
WIRE 16 -1 (-7650 4750)(-7850 4750);
WIRE 16 -1 (-7650 5150)(-7850 5150);
WIRE 16 -1 (-7650 4700)(-7850 4700);
WIRE 16 -1 (-7650 5100)(-7850 5100);
WIRE 16 -1 (-7650 3050)(-8275 3050);
FORCEPROP 2 LAST SIG_NAME M_C_CPU1_ALERT_N
J 0
(-8275 3060);
DISPLAY 0.489362 (-8275 3060);
WIRE 16 -1 (-7650 3550)(-7850 3550);
WIRE 16 -1 (-7650 3700)(-7850 3700);
WIRE 16 -1 (-7650 3850)(-7850 3850);
WIRE 16 -1 (-7650 4000)(-7850 4000);
WIRE 16 -1 (-6450 5400)(-6250 5400);
WIRE 16 -1 (-6600 1425)(-6600 1350);
WIRE 16 -1 (-6600 1425)(-7325 1425);
FORCEPROP 2 LAST SIG_NAME PD_CHC_CPU1_DIMM_SAA
J 0
(-7310 1435);
DISPLAY 0.489362 (-7310 1435);
DOT 1 (-2925 6075);
DOT 1 (-2350 6075);
DOT 1 (-2925 5650);
DOT 1 (-8575 2150);
DOT 1 (-8675 3350);
DOT 1 (-2225 2200);
DOT 1 (-2225 2150);
DOT 1 (-2225 2250);
DOT 1 (-2225 2300);
DOT 1 (-2225 2350);
DOT 1 (-2225 2400);
DOT 1 (-2225 2450);
DOT 1 (-2225 2550);
DOT 1 (-2225 2500);
DOT 1 (-2225 2600);
DOT 1 (-2225 2650);
DOT 1 (-2225 2700);
DOT 1 (-2225 2750);
DOT 1 (-2225 2850);
DOT 1 (-2225 2800);
DOT 1 (-2225 2900);
DOT 1 (-2225 2950);
DOT 1 (-2225 3000);
DOT 1 (-2225 3050);
DOT 1 (-2225 3100);
DOT 1 (-2225 3150);
DOT 1 (-2225 3200);
DOT 1 (-2225 3250);
DOT 1 (-2225 3300);
DOT 1 (-2225 3350);
DOT 1 (-2225 3450);
DOT 1 (-2225 3400);
DOT 1 (-2225 3500);
DOT 1 (-2225 3550);
DOT 1 (-2225 3600);
DOT 1 (-2225 3700);
DOT 1 (-2225 3650);
DOT 1 (-425 2050);
DOT 1 (-425 2150);
DOT 1 (-425 2100);
DOT 1 (-425 2250);
DOT 1 (-425 2300);
DOT 1 (-425 2350);
DOT 1 (-425 2400);
DOT 1 (-425 2450);
DOT 1 (-425 2550);
DOT 1 (-425 2500);
DOT 1 (-425 2600);
DOT 1 (-425 2650);
DOT 1 (-425 2700);
DOT 1 (-425 2750);
DOT 1 (-425 2850);
DOT 1 (-425 2800);
DOT 1 (-425 2900);
DOT 1 (-425 2950);
DOT 1 (-425 3000);
DOT 1 (-425 3050);
DOT 1 (-425 3100);
DOT 1 (-425 3150);
DOT 1 (-425 3200);
DOT 1 (-425 3250);
DOT 1 (-425 3300);
DOT 1 (-425 3350);
DOT 1 (-425 3450);
DOT 1 (-425 3400);
DOT 1 (-425 3500);
DOT 1 (-425 3550);
DOT 1 (-425 3600);
DOT 1 (-425 3700);
DOT 1 (-425 3650);
DOT 1 (-2225 3750);
DOT 1 (-425 3750);
DOT 1 (-2225 3800);
DOT 1 (-2225 3850);
DOT 1 (-2225 3900);
DOT 1 (-2225 3950);
DOT 1 (-2225 4000);
DOT 1 (-2225 4050);
DOT 1 (-2225 4100);
DOT 1 (-2225 4150);
DOT 1 (-2225 4200);
DOT 1 (-2225 4250);
DOT 1 (-2225 4300);
DOT 1 (-2225 4350);
DOT 1 (-2225 4400);
DOT 1 (-2225 4450);
DOT 1 (-2225 4500);
DOT 1 (-2225 4600);
DOT 1 (-2225 4550);
DOT 1 (-2225 4650);
DOT 1 (-2225 4700);
DOT 1 (-2225 4750);
DOT 1 (-2225 4800);
DOT 1 (-2225 4850);
DOT 1 (-2225 4900);
DOT 1 (-2225 4950);
DOT 1 (-2225 5000);
DOT 1 (-2225 5050);
DOT 1 (-2225 5100);
DOT 1 (-2225 5150);
DOT 1 (-2225 5200);
DOT 1 (-2225 5400);
DOT 1 (-2225 5350);
DOT 1 (-425 3800);
DOT 1 (-425 3850);
DOT 1 (-425 3900);
DOT 1 (-425 3950);
DOT 1 (-425 4000);
DOT 1 (-425 4050);
DOT 1 (-425 4100);
DOT 1 (-425 4150);
DOT 1 (-425 4200);
DOT 1 (-425 4250);
DOT 1 (-425 4350);
DOT 1 (-425 4300);
DOT 1 (-425 4400);
DOT 1 (-425 4450);
DOT 1 (-425 4500);
DOT 1 (-425 4550);
DOT 1 (-425 4600);
DOT 1 (-425 4650);
DOT 1 (-425 4700);
DOT 1 (-425 4750);
DOT 1 (-425 4800);
DOT 1 (-425 4850);
DOT 1 (-425 4900);
DOT 1 (-425 4950);
DOT 1 (-425 5000);
DOT 1 (-425 5050);
DOT 1 (-425 5100);
DOT 1 (-425 5150);
DOT 1 (-425 5250);
DOT 1 (-425 5200);
DOT 1 (-425 5300);
DOT 1 (-425 5350);
QUIT
